FILE_TYPE = MACRO_DRAWING;
SET COLOR_WIRE YELLOW;
SET COLOR_PROP ORANGE;
SET COLOR_DOT WHITE;
SET COLOR_ARC YELLOW;
SET COLOR_BODY GREEN;
SET COLOR_NOTE PURPLE;
SET PROP_DISPLAY VALUE;
SET PAGE_NUMBER P18;
FORCEADD GENOA_SP5..9
(-4525 3600);
FORCEPROP 1 LAST LOCATION U25
J 0
(-5170 6431);
DISPLAY 0.489362 (-5170 6431);
PAINT SKYBLUE (-5170 6431);
FORCEPROP 0 LAST $SEC 9
J 0
(-5150 6475);
DISPLAY 0.680851 (-5150 6475);
PAINT MONO (-5150 6475);
DISPLAY INVISIBLE (-5150 6475);
FORCEPROP 0 LAST CDS_SEC 9
J 0
(-5175 6400);
DISPLAY 1.021277 (-5175 6400);
DISPLAY INVISIBLE (-5175 6400);
FORCEPROP 0 LASTPIN (-5325 2975) $PN BC19
J 2
(-5335 2985);
DISPLAY 0.489362 (-5335 2985);
PAINT MONO (-5335 2985);
FORCEPROP 0 LASTPIN (-5325 2925) $PN BD20
J 2
(-5335 2935);
DISPLAY 0.489362 (-5335 2935);
PAINT MONO (-5335 2935);
FORCEPROP 0 LASTPIN (-5325 1825) $PN BF20
J 2
(-5335 1835);
DISPLAY 0.489362 (-5335 1835);
PAINT MONO (-5335 1835);
FORCEPROP 0 LASTPIN (-5325 1775) $PN BG19
J 2
(-5335 1785);
DISPLAY 0.489362 (-5335 1785);
PAINT MONO (-5335 1785);
FORCEPROP 0 LASTPIN (-5325 2125) $PN AT21
J 2
(-5335 2135);
DISPLAY 0.489362 (-5335 2135);
PAINT MONO (-5335 2135);
FORCEPROP 0 LASTPIN (-5325 2025) $PN AU21
J 2
(-5335 2035);
DISPLAY 0.489362 (-5335 2035);
PAINT MONO (-5335 2035);
FORCEPROP 0 LASTPIN (-5325 2825) $PN AU19
J 2
(-5335 2835);
DISPLAY 0.489362 (-5335 2835);
PAINT MONO (-5335 2835);
FORCEPROP 0 LASTPIN (-5325 2775) $PN AV21
J 2
(-5335 2785);
DISPLAY 0.489362 (-5335 2785);
PAINT MONO (-5335 2785);
FORCEPROP 0 LASTPIN (-5325 2675) $PN BN21
J 2
(-5335 2685);
DISPLAY 0.489362 (-5335 2685);
PAINT MONO (-5335 2685);
FORCEPROP 0 LASTPIN (-5325 1675) $PN AV20
J 2
(-5335 1685);
DISPLAY 0.489362 (-5335 1685);
PAINT MONO (-5335 1685);
FORCEPROP 0 LASTPIN (-5325 1625) $PN AW21
J 2
(-5335 1635);
DISPLAY 0.489362 (-5335 1635);
PAINT MONO (-5335 1635);
FORCEPROP 0 LASTPIN (-5325 1525) $PN BP21
J 2
(-5335 1535);
DISPLAY 0.489362 (-5335 1535);
PAINT MONO (-5335 1535);
FORCEPROP 0 LASTPIN (-5325 3825) $PN AW19
J 2
(-5335 3835);
DISPLAY 0.489362 (-5335 3835);
PAINT MONO (-5335 3835);
FORCEPROP 0 LASTPIN (-5325 3775) $PN AY20
J 2
(-5335 3785);
DISPLAY 0.489362 (-5335 3785);
PAINT MONO (-5335 3785);
FORCEPROP 0 LASTPIN (-5325 3725) $PN AY21
J 2
(-5335 3735);
DISPLAY 0.489362 (-5335 3735);
PAINT MONO (-5335 3735);
FORCEPROP 0 LASTPIN (-5325 3675) $PN BA21
J 2
(-5335 3685);
DISPLAY 0.489362 (-5335 3685);
PAINT MONO (-5335 3685);
FORCEPROP 0 LASTPIN (-5325 3625) $PN BA19
J 2
(-5335 3635);
DISPLAY 0.489362 (-5335 3635);
PAINT MONO (-5335 3635);
FORCEPROP 0 LASTPIN (-5325 3575) $PN BB20
J 2
(-5335 3585);
DISPLAY 0.489362 (-5335 3585);
PAINT MONO (-5335 3585);
FORCEPROP 0 LASTPIN (-5325 3525) $PN BB21
J 2
(-5335 3535);
DISPLAY 0.489362 (-5335 3535);
PAINT MONO (-5335 3535);
FORCEPROP 0 LASTPIN (-3725 2375) $PN AJ19
J 0
(-3715 2385);
DISPLAY 0.489362 (-3715 2385);
PAINT MONO (-3715 2385);
FORCEPROP 0 LASTPIN (-3725 2325) $PN AK21
J 0
(-3715 2335);
DISPLAY 0.489362 (-3715 2335);
PAINT MONO (-3715 2335);
FORCEPROP 0 LASTPIN (-3725 2275) $PN AK20
J 0
(-3715 2285);
DISPLAY 0.489362 (-3715 2285);
PAINT MONO (-3715 2285);
FORCEPROP 0 LASTPIN (-3725 2225) $PN AL21
J 0
(-3715 2235);
DISPLAY 0.489362 (-3715 2235);
PAINT MONO (-3715 2235);
FORCEPROP 0 LASTPIN (-3725 2175) $PN AN19
J 0
(-3715 2185);
DISPLAY 0.489362 (-3715 2185);
PAINT MONO (-3715 2185);
FORCEPROP 0 LASTPIN (-3725 2125) $PN AP21
J 0
(-3715 2135);
DISPLAY 0.489362 (-3715 2135);
PAINT MONO (-3715 2135);
FORCEPROP 0 LASTPIN (-3725 2075) $PN AP20
J 0
(-3715 2085);
DISPLAY 0.489362 (-3715 2085);
PAINT MONO (-3715 2085);
FORCEPROP 0 LASTPIN (-3725 2025) $PN AR21
J 0
(-3715 2035);
DISPLAY 0.489362 (-3715 2035);
PAINT MONO (-3715 2035);
FORCEPROP 0 LASTPIN (-3725 5975) $PN E19
J 0
(-3715 5985);
DISPLAY 0.489362 (-3715 5985);
PAINT MONO (-3715 5985);
FORCEPROP 0 LASTPIN (-3725 5925) $PN F21
J 0
(-3715 5935);
DISPLAY 0.489362 (-3715 5935);
PAINT MONO (-3715 5935);
FORCEPROP 0 LASTPIN (-3725 5875) $PN F20
J 0
(-3715 5885);
DISPLAY 0.489362 (-3715 5885);
PAINT MONO (-3715 5885);
FORCEPROP 0 LASTPIN (-3725 5825) $PN G21
J 0
(-3715 5835);
DISPLAY 0.489362 (-3715 5835);
PAINT MONO (-3715 5835);
FORCEPROP 0 LASTPIN (-3725 5775) $PN J19
J 0
(-3715 5785);
DISPLAY 0.489362 (-3715 5785);
PAINT MONO (-3715 5785);
FORCEPROP 0 LASTPIN (-3725 5725) $PN K21
J 0
(-3715 5735);
DISPLAY 0.489362 (-3715 5735);
PAINT MONO (-3715 5735);
FORCEPROP 0 LASTPIN (-3725 5675) $PN K20
J 0
(-3715 5685);
DISPLAY 0.489362 (-3715 5685);
PAINT MONO (-3715 5685);
FORCEPROP 0 LASTPIN (-3725 5625) $PN L21
J 0
(-3715 5635);
DISPLAY 0.489362 (-3715 5635);
PAINT MONO (-3715 5635);
FORCEPROP 0 LASTPIN (-3725 5525) $PN L19
J 0
(-3715 5535);
DISPLAY 0.489362 (-3715 5535);
PAINT MONO (-3715 5535);
FORCEPROP 0 LASTPIN (-3725 5475) $PN M21
J 0
(-3715 5485);
DISPLAY 0.489362 (-3715 5485);
PAINT MONO (-3715 5485);
FORCEPROP 0 LASTPIN (-3725 5425) $PN M20
J 0
(-3715 5435);
DISPLAY 0.489362 (-3715 5435);
PAINT MONO (-3715 5435);
FORCEPROP 0 LASTPIN (-3725 5375) $PN N21
J 0
(-3715 5385);
DISPLAY 0.489362 (-3715 5385);
PAINT MONO (-3715 5385);
FORCEPROP 0 LASTPIN (-3725 5325) $PN R19
J 0
(-3715 5335);
DISPLAY 0.489362 (-3715 5335);
PAINT MONO (-3715 5335);
FORCEPROP 0 LASTPIN (-3725 5275) $PN T21
J 0
(-3715 5285);
DISPLAY 0.489362 (-3715 5285);
PAINT MONO (-3715 5285);
FORCEPROP 0 LASTPIN (-3725 5225) $PN T20
J 0
(-3715 5235);
DISPLAY 0.489362 (-3715 5235);
PAINT MONO (-3715 5235);
FORCEPROP 0 LASTPIN (-3725 5175) $PN U21
J 0
(-3715 5185);
DISPLAY 0.489362 (-3715 5185);
PAINT MONO (-3715 5185);
FORCEPROP 0 LASTPIN (-3725 5075) $PN U19
J 0
(-3715 5085);
DISPLAY 0.489362 (-3715 5085);
PAINT MONO (-3715 5085);
FORCEPROP 0 LASTPIN (-3725 5025) $PN V21
J 0
(-3715 5035);
DISPLAY 0.489362 (-3715 5035);
PAINT MONO (-3715 5035);
FORCEPROP 0 LASTPIN (-3725 4975) $PN V20
J 0
(-3715 4985);
DISPLAY 0.489362 (-3715 4985);
PAINT MONO (-3715 4985);
FORCEPROP 0 LASTPIN (-3725 4925) $PN W21
J 0
(-3715 4935);
DISPLAY 0.489362 (-3715 4935);
PAINT MONO (-3715 4935);
FORCEPROP 0 LASTPIN (-3725 4875) $PN AA19
J 0
(-3715 4885);
DISPLAY 0.489362 (-3715 4885);
PAINT MONO (-3715 4885);
FORCEPROP 0 LASTPIN (-3725 4825) $PN AB21
J 0
(-3715 4835);
DISPLAY 0.489362 (-3715 4835);
PAINT MONO (-3715 4835);
FORCEPROP 0 LASTPIN (-3725 4775) $PN AB20
J 0
(-3715 4785);
DISPLAY 0.489362 (-3715 4785);
PAINT MONO (-3715 4785);
FORCEPROP 0 LASTPIN (-3725 4725) $PN AC21
J 0
(-3715 4735);
DISPLAY 0.489362 (-3715 4735);
PAINT MONO (-3715 4735);
FORCEPROP 0 LASTPIN (-3725 4625) $PN AC19
J 0
(-3715 4635);
DISPLAY 0.489362 (-3715 4635);
PAINT MONO (-3715 4635);
FORCEPROP 0 LASTPIN (-3725 4575) $PN AD21
J 0
(-3715 4585);
DISPLAY 0.489362 (-3715 4585);
PAINT MONO (-3715 4585);
FORCEPROP 0 LASTPIN (-3725 4525) $PN AD20
J 0
(-3715 4535);
DISPLAY 0.489362 (-3715 4535);
PAINT MONO (-3715 4535);
FORCEPROP 0 LASTPIN (-3725 4475) $PN AE21
J 0
(-3715 4485);
DISPLAY 0.489362 (-3715 4485);
PAINT MONO (-3715 4485);
FORCEPROP 0 LASTPIN (-3725 4425) $PN AG19
J 0
(-3715 4435);
DISPLAY 0.489362 (-3715 4435);
PAINT MONO (-3715 4435);
FORCEPROP 0 LASTPIN (-3725 4375) $PN AH21
J 0
(-3715 4385);
DISPLAY 0.489362 (-3715 4385);
PAINT MONO (-3715 4385);
FORCEPROP 0 LASTPIN (-3725 4325) $PN AH20
J 0
(-3715 4335);
DISPLAY 0.489362 (-3715 4335);
PAINT MONO (-3715 4335);
FORCEPROP 0 LASTPIN (-3725 4275) $PN AJ21
J 0
(-3715 4285);
DISPLAY 0.489362 (-3715 4285);
PAINT MONO (-3715 4285);
FORCEPROP 0 LASTPIN (-5325 5975) $PN G19
J 2
(-5335 5985);
DISPLAY 0.489362 (-5335 5985);
PAINT MONO (-5335 5985);
FORCEPROP 0 LASTPIN (-5325 5875) $PN N19
J 2
(-5335 5885);
DISPLAY 0.489362 (-5335 5885);
PAINT MONO (-5335 5885);
FORCEPROP 0 LASTPIN (-5325 5775) $PN W19
J 2
(-5335 5785);
DISPLAY 0.489362 (-5335 5785);
PAINT MONO (-5335 5785);
FORCEPROP 0 LASTPIN (-5325 5675) $PN AE19
J 2
(-5335 5685);
DISPLAY 0.489362 (-5335 5685);
PAINT MONO (-5335 5685);
FORCEPROP 0 LASTPIN (-5325 5575) $PN AL19
J 2
(-5335 5585);
DISPLAY 0.489362 (-5335 5585);
PAINT MONO (-5335 5585);
FORCEPROP 0 LASTPIN (-5325 5475) $PN J21
J 2
(-5335 5485);
DISPLAY 0.489362 (-5335 5485);
PAINT MONO (-5335 5485);
FORCEPROP 0 LASTPIN (-5325 5375) $PN R21
J 2
(-5335 5385);
DISPLAY 0.489362 (-5335 5385);
PAINT MONO (-5335 5385);
FORCEPROP 0 LASTPIN (-5325 5275) $PN AA21
J 2
(-5335 5285);
DISPLAY 0.489362 (-5335 5285);
PAINT MONO (-5335 5285);
FORCEPROP 0 LASTPIN (-5325 5175) $PN AG21
J 2
(-5335 5185);
DISPLAY 0.489362 (-5335 5185);
PAINT MONO (-5335 5185);
FORCEPROP 0 LASTPIN (-5325 5075) $PN AN21
J 2
(-5335 5085);
DISPLAY 0.489362 (-5335 5085);
PAINT MONO (-5335 5085);
FORCEPROP 0 LASTPIN (-5325 5925) $PN H20
J 2
(-5335 5935);
DISPLAY 0.489362 (-5335 5935);
PAINT MONO (-5335 5935);
FORCEPROP 0 LASTPIN (-5325 5825) $PN P20
J 2
(-5335 5835);
DISPLAY 0.489362 (-5335 5835);
PAINT MONO (-5335 5835);
FORCEPROP 0 LASTPIN (-5325 5725) $PN Y20
J 2
(-5335 5735);
DISPLAY 0.489362 (-5335 5735);
PAINT MONO (-5335 5735);
FORCEPROP 0 LASTPIN (-5325 5625) $PN AF20
J 2
(-5335 5635);
DISPLAY 0.489362 (-5335 5635);
PAINT MONO (-5335 5635);
FORCEPROP 0 LASTPIN (-5325 5525) $PN AM20
J 2
(-5335 5535);
DISPLAY 0.489362 (-5335 5535);
PAINT MONO (-5335 5535);
FORCEPROP 0 LASTPIN (-5325 5425) $PN H21
J 2
(-5335 5435);
DISPLAY 0.489362 (-5335 5435);
PAINT MONO (-5335 5435);
FORCEPROP 0 LASTPIN (-5325 5325) $PN P21
J 2
(-5335 5335);
DISPLAY 0.489362 (-5335 5335);
PAINT MONO (-5335 5335);
FORCEPROP 0 LASTPIN (-5325 5225) $PN Y21
J 2
(-5335 5235);
DISPLAY 0.489362 (-5335 5235);
PAINT MONO (-5335 5235);
FORCEPROP 0 LASTPIN (-5325 5125) $PN AF21
J 2
(-5335 5135);
DISPLAY 0.489362 (-5335 5135);
PAINT MONO (-5335 5135);
FORCEPROP 0 LASTPIN (-5325 5025) $PN AM21
J 2
(-5335 5035);
DISPLAY 0.489362 (-5335 5035);
PAINT MONO (-5335 5035);
FORCEPROP 0 LASTPIN (-5325 2575) $PN BC21
J 2
(-5335 2585);
DISPLAY 0.489362 (-5335 2585);
PAINT MONO (-5335 2585);
FORCEPROP 0 LASTPIN (-5325 2475) $PN BM21
J 2
(-5335 2485);
DISPLAY 0.489362 (-5335 2485);
PAINT MONO (-5335 2485);
FORCEPROP 0 LASTPIN (-5325 2425) $PN BN19
J 2
(-5335 2435);
DISPLAY 0.489362 (-5335 2435);
PAINT MONO (-5335 2435);
FORCEPROP 0 LASTPIN (-5325 2325) $PN BP20
J 2
(-5335 2335);
DISPLAY 0.489362 (-5335 2335);
PAINT MONO (-5335 2335);
FORCEPROP 0 LASTPIN (-5325 1425) $PN BL19
J 2
(-5335 1435);
DISPLAY 0.489362 (-5335 1435);
PAINT MONO (-5335 1435);
FORCEPROP 0 LASTPIN (-5325 1375) $PN BM20
J 2
(-5335 1385);
DISPLAY 0.489362 (-5335 1385);
PAINT MONO (-5335 1385);
FORCEPROP 0 LASTPIN (-5325 1275) $PN BR19
J 2
(-5335 1285);
DISPLAY 0.489362 (-5335 1285);
PAINT MONO (-5335 1285);
FORCEPROP 0 LASTPIN (-5325 3425) $PN BG21
J 2
(-5335 3435);
DISPLAY 0.489362 (-5335 3435);
PAINT MONO (-5335 3435);
FORCEPROP 0 LASTPIN (-5325 3375) $PN BH21
J 2
(-5335 3385);
DISPLAY 0.489362 (-5335 3385);
PAINT MONO (-5335 3385);
FORCEPROP 0 LASTPIN (-5325 3325) $PN BH20
J 2
(-5335 3335);
DISPLAY 0.489362 (-5335 3335);
PAINT MONO (-5335 3335);
FORCEPROP 0 LASTPIN (-5325 3275) $PN BJ19
J 2
(-5335 3285);
DISPLAY 0.489362 (-5335 3285);
PAINT MONO (-5335 3285);
FORCEPROP 0 LASTPIN (-5325 3225) $PN BJ21
J 2
(-5335 3235);
DISPLAY 0.489362 (-5335 3235);
PAINT MONO (-5335 3235);
FORCEPROP 0 LASTPIN (-5325 3175) $PN BK21
J 2
(-5335 3185);
DISPLAY 0.489362 (-5335 3185);
PAINT MONO (-5335 3185);
FORCEPROP 0 LASTPIN (-5325 3125) $PN BK20
J 2
(-5335 3135);
DISPLAY 0.489362 (-5335 3135);
PAINT MONO (-5335 3135);
FORCEPROP 0 LASTPIN (-3725 1925) $PN BY20
J 0
(-3715 1935);
DISPLAY 0.489362 (-3715 1935);
PAINT MONO (-3715 1935);
FORCEPROP 0 LASTPIN (-3725 1875) $PN CA21
J 0
(-3715 1885);
DISPLAY 0.489362 (-3715 1885);
PAINT MONO (-3715 1885);
FORCEPROP 0 LASTPIN (-3725 1825) $PN CA19
J 0
(-3715 1835);
DISPLAY 0.489362 (-3715 1835);
PAINT MONO (-3715 1835);
FORCEPROP 0 LASTPIN (-3725 1775) $PN CB21
J 0
(-3715 1785);
DISPLAY 0.489362 (-3715 1785);
PAINT MONO (-3715 1785);
FORCEPROP 0 LASTPIN (-3725 1725) $PN BT20
J 0
(-3715 1735);
DISPLAY 0.489362 (-3715 1735);
PAINT MONO (-3715 1735);
FORCEPROP 0 LASTPIN (-3725 1675) $PN BU21
J 0
(-3715 1685);
DISPLAY 0.489362 (-3715 1685);
PAINT MONO (-3715 1685);
FORCEPROP 0 LASTPIN (-3725 1625) $PN BU19
J 0
(-3715 1635);
DISPLAY 0.489362 (-3715 1635);
PAINT MONO (-3715 1635);
FORCEPROP 0 LASTPIN (-3725 1575) $PN BV21
J 0
(-3715 1585);
DISPLAY 0.489362 (-3715 1585);
PAINT MONO (-3715 1585);
FORCEPROP 0 LASTPIN (-3725 4175) $PN CB20
J 0
(-3715 4185);
DISPLAY 0.489362 (-3715 4185);
PAINT MONO (-3715 4185);
FORCEPROP 0 LASTPIN (-3725 4125) $PN CC21
J 0
(-3715 4135);
DISPLAY 0.489362 (-3715 4135);
PAINT MONO (-3715 4135);
FORCEPROP 0 LASTPIN (-3725 4075) $PN CC19
J 0
(-3715 4085);
DISPLAY 0.489362 (-3715 4085);
PAINT MONO (-3715 4085);
FORCEPROP 0 LASTPIN (-3725 4025) $PN CD21
J 0
(-3715 4035);
DISPLAY 0.489362 (-3715 4035);
PAINT MONO (-3715 4035);
FORCEPROP 0 LASTPIN (-3725 3975) $PN CF20
J 0
(-3715 3985);
DISPLAY 0.489362 (-3715 3985);
PAINT MONO (-3715 3985);
FORCEPROP 0 LASTPIN (-3725 3925) $PN CG21
J 0
(-3715 3935);
DISPLAY 0.489362 (-3715 3935);
PAINT MONO (-3715 3935);
FORCEPROP 0 LASTPIN (-3725 3875) $PN CG19
J 0
(-3715 3885);
DISPLAY 0.489362 (-3715 3885);
PAINT MONO (-3715 3885);
FORCEPROP 0 LASTPIN (-3725 3825) $PN CH21
J 0
(-3715 3835);
DISPLAY 0.489362 (-3715 3835);
PAINT MONO (-3715 3835);
FORCEPROP 0 LASTPIN (-3725 3725) $PN CH20
J 0
(-3715 3735);
DISPLAY 0.489362 (-3715 3735);
PAINT MONO (-3715 3735);
FORCEPROP 0 LASTPIN (-3725 3675) $PN CJ21
J 0
(-3715 3685);
DISPLAY 0.489362 (-3715 3685);
PAINT MONO (-3715 3685);
FORCEPROP 0 LASTPIN (-3725 3625) $PN CJ19
J 0
(-3715 3635);
DISPLAY 0.489362 (-3715 3635);
PAINT MONO (-3715 3635);
FORCEPROP 0 LASTPIN (-3725 3575) $PN CK21
J 0
(-3715 3585);
DISPLAY 0.489362 (-3715 3585);
PAINT MONO (-3715 3585);
FORCEPROP 0 LASTPIN (-3725 3525) $PN CM20
J 0
(-3715 3535);
DISPLAY 0.489362 (-3715 3535);
PAINT MONO (-3715 3535);
FORCEPROP 0 LASTPIN (-3725 3475) $PN CN21
J 0
(-3715 3485);
DISPLAY 0.489362 (-3715 3485);
PAINT MONO (-3715 3485);
FORCEPROP 0 LASTPIN (-3725 3425) $PN CN19
J 0
(-3715 3435);
DISPLAY 0.489362 (-3715 3435);
PAINT MONO (-3715 3435);
FORCEPROP 0 LASTPIN (-3725 3375) $PN CP21
J 0
(-3715 3385);
DISPLAY 0.489362 (-3715 3385);
PAINT MONO (-3715 3385);
FORCEPROP 0 LASTPIN (-3725 3275) $PN CP20
J 0
(-3715 3285);
DISPLAY 0.489362 (-3715 3285);
PAINT MONO (-3715 3285);
FORCEPROP 0 LASTPIN (-3725 3225) $PN CR21
J 0
(-3715 3235);
DISPLAY 0.489362 (-3715 3235);
PAINT MONO (-3715 3235);
FORCEPROP 0 LASTPIN (-3725 3175) $PN CR19
J 0
(-3715 3185);
DISPLAY 0.489362 (-3715 3185);
PAINT MONO (-3715 3185);
FORCEPROP 0 LASTPIN (-3725 3125) $PN CT21
J 0
(-3715 3135);
DISPLAY 0.489362 (-3715 3135);
PAINT MONO (-3715 3135);
FORCEPROP 0 LASTPIN (-3725 3075) $PN CV20
J 0
(-3715 3085);
DISPLAY 0.489362 (-3715 3085);
PAINT MONO (-3715 3085);
FORCEPROP 0 LASTPIN (-3725 3025) $PN CW21
J 0
(-3715 3035);
DISPLAY 0.489362 (-3715 3035);
PAINT MONO (-3715 3035);
FORCEPROP 0 LASTPIN (-3725 2975) $PN CW19
J 0
(-3715 2985);
DISPLAY 0.489362 (-3715 2985);
PAINT MONO (-3715 2985);
FORCEPROP 0 LASTPIN (-3725 2925) $PN CY21
J 0
(-3715 2935);
DISPLAY 0.489362 (-3715 2935);
PAINT MONO (-3715 2935);
FORCEPROP 0 LASTPIN (-3725 2825) $PN CY20
J 0
(-3715 2835);
DISPLAY 0.489362 (-3715 2835);
PAINT MONO (-3715 2835);
FORCEPROP 0 LASTPIN (-3725 2775) $PN DA21
J 0
(-3715 2785);
DISPLAY 0.489362 (-3715 2785);
PAINT MONO (-3715 2785);
FORCEPROP 0 LASTPIN (-3725 2725) $PN DA19
J 0
(-3715 2735);
DISPLAY 0.489362 (-3715 2735);
PAINT MONO (-3715 2735);
FORCEPROP 0 LASTPIN (-3725 2675) $PN DB21
J 0
(-3715 2685);
DISPLAY 0.489362 (-3715 2685);
PAINT MONO (-3715 2685);
FORCEPROP 0 LASTPIN (-3725 2625) $PN DD20
J 0
(-3715 2635);
DISPLAY 0.489362 (-3715 2635);
PAINT MONO (-3715 2635);
FORCEPROP 0 LASTPIN (-3725 2575) $PN DE21
J 0
(-3715 2585);
DISPLAY 0.489362 (-3715 2585);
PAINT MONO (-3715 2585);
FORCEPROP 0 LASTPIN (-3725 2525) $PN DE19
J 0
(-3715 2535);
DISPLAY 0.489362 (-3715 2535);
PAINT MONO (-3715 2535);
FORCEPROP 0 LASTPIN (-3725 2475) $PN DF21
J 0
(-3715 2485);
DISPLAY 0.489362 (-3715 2485);
PAINT MONO (-3715 2485);
FORCEPROP 0 LASTPIN (-5325 4925) $PN CD20
J 2
(-5335 4935);
DISPLAY 0.489362 (-5335 4935);
PAINT MONO (-5335 4935);
FORCEPROP 0 LASTPIN (-5325 4825) $PN CK20
J 2
(-5335 4835);
DISPLAY 0.489362 (-5335 4835);
PAINT MONO (-5335 4835);
FORCEPROP 0 LASTPIN (-5325 4725) $PN CT20
J 2
(-5335 4735);
DISPLAY 0.489362 (-5335 4735);
PAINT MONO (-5335 4735);
FORCEPROP 0 LASTPIN (-5325 4625) $PN DB20
J 2
(-5335 4635);
DISPLAY 0.489362 (-5335 4635);
PAINT MONO (-5335 4635);
FORCEPROP 0 LASTPIN (-5325 4525) $PN BY21
J 2
(-5335 4535);
DISPLAY 0.489362 (-5335 4535);
PAINT MONO (-5335 4535);
FORCEPROP 0 LASTPIN (-5325 4425) $PN CF21
J 2
(-5335 4435);
DISPLAY 0.489362 (-5335 4435);
PAINT MONO (-5335 4435);
FORCEPROP 0 LASTPIN (-5325 4325) $PN CM21
J 2
(-5335 4335);
DISPLAY 0.489362 (-5335 4335);
PAINT MONO (-5335 4335);
FORCEPROP 0 LASTPIN (-5325 4225) $PN CV21
J 2
(-5335 4235);
DISPLAY 0.489362 (-5335 4235);
PAINT MONO (-5335 4235);
FORCEPROP 0 LASTPIN (-5325 4125) $PN DD21
J 2
(-5335 4135);
DISPLAY 0.489362 (-5335 4135);
PAINT MONO (-5335 4135);
FORCEPROP 0 LASTPIN (-5325 4025) $PN BV20
J 2
(-5335 4035);
DISPLAY 0.489362 (-5335 4035);
PAINT MONO (-5335 4035);
FORCEPROP 0 LASTPIN (-5325 4875) $PN CE19
J 2
(-5335 4885);
DISPLAY 0.489362 (-5335 4885);
PAINT MONO (-5335 4885);
FORCEPROP 0 LASTPIN (-5325 4775) $PN CL19
J 2
(-5335 4785);
DISPLAY 0.489362 (-5335 4785);
PAINT MONO (-5335 4785);
FORCEPROP 0 LASTPIN (-5325 4675) $PN CU19
J 2
(-5335 4685);
DISPLAY 0.489362 (-5335 4685);
PAINT MONO (-5335 4685);
FORCEPROP 0 LASTPIN (-5325 4575) $PN DC19
J 2
(-5335 4585);
DISPLAY 0.489362 (-5335 4585);
PAINT MONO (-5335 4585);
FORCEPROP 0 LASTPIN (-5325 4475) $PN BW21
J 2
(-5335 4485);
DISPLAY 0.489362 (-5335 4485);
PAINT MONO (-5335 4485);
FORCEPROP 0 LASTPIN (-5325 4375) $PN CE21
J 2
(-5335 4385);
DISPLAY 0.489362 (-5335 4385);
PAINT MONO (-5335 4385);
FORCEPROP 0 LASTPIN (-5325 4275) $PN CL21
J 2
(-5335 4285);
DISPLAY 0.489362 (-5335 4285);
PAINT MONO (-5335 4285);
FORCEPROP 0 LASTPIN (-5325 4175) $PN CU21
J 2
(-5335 4185);
DISPLAY 0.489362 (-5335 4185);
PAINT MONO (-5335 4185);
FORCEPROP 0 LASTPIN (-5325 4075) $PN DC21
J 2
(-5335 4085);
DISPLAY 0.489362 (-5335 4085);
PAINT MONO (-5335 4085);
FORCEPROP 0 LASTPIN (-5325 3975) $PN BW19
J 2
(-5335 3985);
DISPLAY 0.489362 (-5335 3985);
PAINT MONO (-5335 3985);
FORCEPROP 0 LASTPIN (-5325 2225) $PN BL21
J 2
(-5335 2235);
DISPLAY 0.489362 (-5335 2235);
PAINT MONO (-5335 2235);
FORCEPROP 0 LASTPIN (-5325 1175) $PN BF21
J 2
(-5335 1185);
DISPLAY 0.489362 (-5335 1185);
PAINT MONO (-5335 1185);
FORCEPROP 2 LAST PART_TYPE SMLF
J 0
(-5175 6350);
DISPLAY 1.021277 (-5175 6350);
FORCEPROP 1 LAST MATERIAL IO
J 0
(-5170 6157);
DISPLAY 0.489362 (-5170 6157);
PAINT SKYBLUE (-5170 6157);
FORCEPROP 2 LAST VALUE SOCKET6096_13568-001
J 0
(-5175 6250);
DISPLAY 0.489362 (-5175 6250);
PAINT SKYBLUE (-5175 6250);
FORCEPROP 2 LAST CDS_LIB pure_quanta
J 0
(-4525 3600);
DISPLAY INVISIBLE (-4525 3600);
FORCEPROP 1 LAST CDS_LMAN_SYM_OUTLINE -650,2525,650,-2525
J 0
(-4525 3600);
DISPLAY 0.468085 (-4525 3600);
PAINT GREEN (-4525 3600);
DISPLAY INVISIBLE (-4525 3600);
FORCEPROP 1 LAST NEEDS_NO_SIZE TRUE
J 0
(-4525 3600);
DISPLAY 0.723404 (-4525 3600);
PAINT GREEN (-4525 3600);
DISPLAY INVISIBLE (-4525 3600);
FORCEPROP 1 LAST PATH I159
J 0
(-4525 3600);
DISPLAY 0.723404 (-4525 3600);
PAINT GREEN (-4525 3600);
DISPLAY INVISIBLE (-4525 3600);
FORCEPROP 1 LAST PART_NUMBER DGA^6000030
J 0
(-5170 6284);
DISPLAY 0.489362 (-5170 6284);
PAINT SKYBLUE (-5170 6284);
DISPLAY INVISIBLE (-5170 6284);
FORCEADD OFFPAGE..3
(-2525 6000);
FORCEPROP 2 LAST $XR0 94 
J 0
(-2311 6000);
DISPLAY 0.638298 (-2311 6000);
PAINT MONO (-2311 6000);
FORCEPROP 2 LAST CDS_LIB mstr_standard
J 0
(-2525 6000);
DISPLAY 0.723404 (-2525 6000);
PAINT MONO (-2525 6000);
DISPLAY INVISIBLE (-2525 6000);
FORCEPROP 1 LAST OFFPAGE TRUE
J 0
(-2200 5875);
DISPLAY 0.872340 (-2200 5875);
PAINT GREEN (-2200 5875);
DISPLAY INVISIBLE (-2200 5875);
FORCEPROP 1 LAST COMMENT_BODY TRUE
J 0
(-2575 5900);
DISPLAY 0.872340 (-2575 5900);
PAINT GREEN (-2575 5900);
DISPLAY INVISIBLE (-2575 5900);
FORCEPROP 2 LAST PATH I160
J 0
(-2300 6050);
DISPLAY 1.021277 (-2300 6050);
DISPLAY INVISIBLE (-2300 6050);
FORCEADD OFFPAGE..3
(-2525 4200);
FORCEPROP 2 LAST $XR0 94 
J 0
(-2311 4200);
DISPLAY 0.638298 (-2311 4200);
PAINT MONO (-2311 4200);
FORCEPROP 2 LAST CDS_LIB mstr_standard
J 0
(-2525 4200);
DISPLAY 0.723404 (-2525 4200);
PAINT MONO (-2525 4200);
DISPLAY INVISIBLE (-2525 4200);
FORCEPROP 1 LAST OFFPAGE TRUE
J 0
(-2200 4075);
DISPLAY 0.872340 (-2200 4075);
PAINT GREEN (-2200 4075);
DISPLAY INVISIBLE (-2200 4075);
FORCEPROP 1 LAST COMMENT_BODY TRUE
J 0
(-2575 4100);
DISPLAY 0.872340 (-2575 4100);
PAINT GREEN (-2575 4100);
DISPLAY INVISIBLE (-2575 4100);
FORCEPROP 2 LAST PATH I161
J 0
(-2300 4250);
DISPLAY 1.021277 (-2300 4250);
DISPLAY INVISIBLE (-2300 4250);
FORCEADD TAP..1
(-3250 5975);
FORCEPROP 3 LASTPIN (-3300 5975) SIG_NAME M_I_CPU0_SA_DQ<0>
J 0
(-3290 5985);
DISPLAY 0.659574 (-3290 5985);
PAINT MONO (-3290 5985);
DISPLAY INVISIBLE (-3290 5985);
FORCEPROP 1 LASTPIN (-3300 5975) BN 0
J 0
(-3312 5983);
DISPLAY 0.489362 (-3312 5983);
PAINT GREEN (-3312 5983);
FORCEPROP 2 LAST CDS_LIB mstr_standard
J 0
(-3250 5975);
DISPLAY 0.723404 (-3250 5975);
PAINT MONO (-3250 5975);
DISPLAY INVISIBLE (-3250 5975);
FORCEPROP 1 LAST BODY_TYPE PLUMBING
J 0
(-3250 6025);
DISPLAY 0.872340 (-3250 6025);
PAINT GREEN (-3250 6025);
DISPLAY INVISIBLE (-3250 6025);
FORCEPROP 1 LAST HDL_TAP TRUE
J 0
(-2925 5850);
DISPLAY 0.872340 (-2925 5850);
DISPLAY INVISIBLE (-2925 5850);
FORCEPROP 1 LAST PATH I162
J 0
(-3252 5975);
DISPLAY 0.872340 (-3252 5975);
PAINT GREEN (-3252 5975);
DISPLAY INVISIBLE (-3252 5975);
FORCEADD TAP..1
(-3250 5925);
FORCEPROP 3 LASTPIN (-3300 5925) SIG_NAME M_I_CPU0_SA_DQ<1>
J 0
(-3290 5935);
DISPLAY 0.659574 (-3290 5935);
PAINT MONO (-3290 5935);
DISPLAY INVISIBLE (-3290 5935);
FORCEPROP 1 LASTPIN (-3300 5925) BN 1
J 0
(-3312 5933);
DISPLAY 0.489362 (-3312 5933);
PAINT GREEN (-3312 5933);
FORCEPROP 2 LAST CDS_LIB mstr_standard
J 0
(-3250 5925);
DISPLAY 0.723404 (-3250 5925);
PAINT MONO (-3250 5925);
DISPLAY INVISIBLE (-3250 5925);
FORCEPROP 1 LAST BODY_TYPE PLUMBING
J 0
(-3250 5975);
DISPLAY 0.872340 (-3250 5975);
PAINT GREEN (-3250 5975);
DISPLAY INVISIBLE (-3250 5975);
FORCEPROP 1 LAST HDL_TAP TRUE
J 0
(-2925 5800);
DISPLAY 0.872340 (-2925 5800);
DISPLAY INVISIBLE (-2925 5800);
FORCEPROP 1 LAST PATH I163
J 0
(-3252 5925);
DISPLAY 0.872340 (-3252 5925);
PAINT GREEN (-3252 5925);
DISPLAY INVISIBLE (-3252 5925);
FORCEADD TAP..1
(-3250 5775);
FORCEPROP 3 LASTPIN (-3300 5775) SIG_NAME M_I_CPU0_SA_DQ<4>
J 0
(-3290 5785);
DISPLAY 0.659574 (-3290 5785);
PAINT MONO (-3290 5785);
DISPLAY INVISIBLE (-3290 5785);
FORCEPROP 1 LASTPIN (-3300 5775) BN 4
J 0
(-3312 5783);
DISPLAY 0.489362 (-3312 5783);
PAINT GREEN (-3312 5783);
FORCEPROP 2 LAST CDS_LIB mstr_standard
J 0
(-3250 5775);
DISPLAY 0.723404 (-3250 5775);
PAINT MONO (-3250 5775);
DISPLAY INVISIBLE (-3250 5775);
FORCEPROP 1 LAST BODY_TYPE PLUMBING
J 0
(-3250 5825);
DISPLAY 0.872340 (-3250 5825);
PAINT GREEN (-3250 5825);
DISPLAY INVISIBLE (-3250 5825);
FORCEPROP 1 LAST HDL_TAP TRUE
J 0
(-2925 5650);
DISPLAY 0.872340 (-2925 5650);
DISPLAY INVISIBLE (-2925 5650);
FORCEPROP 1 LAST PATH I164
J 0
(-3252 5775);
DISPLAY 0.872340 (-3252 5775);
PAINT GREEN (-3252 5775);
DISPLAY INVISIBLE (-3252 5775);
FORCEADD TAP..1
(-3250 5825);
FORCEPROP 3 LASTPIN (-3300 5825) SIG_NAME M_I_CPU0_SA_DQ<3>
J 0
(-3290 5835);
DISPLAY 0.659574 (-3290 5835);
PAINT MONO (-3290 5835);
DISPLAY INVISIBLE (-3290 5835);
FORCEPROP 1 LASTPIN (-3300 5825) BN 3
J 0
(-3312 5833);
DISPLAY 0.489362 (-3312 5833);
PAINT GREEN (-3312 5833);
FORCEPROP 2 LAST CDS_LIB mstr_standard
J 0
(-3250 5825);
DISPLAY 0.723404 (-3250 5825);
PAINT MONO (-3250 5825);
DISPLAY INVISIBLE (-3250 5825);
FORCEPROP 1 LAST BODY_TYPE PLUMBING
J 0
(-3250 5875);
DISPLAY 0.872340 (-3250 5875);
PAINT GREEN (-3250 5875);
DISPLAY INVISIBLE (-3250 5875);
FORCEPROP 1 LAST HDL_TAP TRUE
J 0
(-2925 5700);
DISPLAY 0.872340 (-2925 5700);
DISPLAY INVISIBLE (-2925 5700);
FORCEPROP 1 LAST PATH I165
J 0
(-3252 5825);
DISPLAY 0.872340 (-3252 5825);
PAINT GREEN (-3252 5825);
DISPLAY INVISIBLE (-3252 5825);
FORCEADD TAP..1
(-3250 5875);
FORCEPROP 3 LASTPIN (-3300 5875) SIG_NAME M_I_CPU0_SA_DQ<2>
J 0
(-3290 5885);
DISPLAY 0.659574 (-3290 5885);
PAINT MONO (-3290 5885);
DISPLAY INVISIBLE (-3290 5885);
FORCEPROP 1 LASTPIN (-3300 5875) BN 2
J 0
(-3312 5883);
DISPLAY 0.489362 (-3312 5883);
PAINT GREEN (-3312 5883);
FORCEPROP 2 LAST CDS_LIB mstr_standard
J 0
(-3250 5875);
DISPLAY 0.723404 (-3250 5875);
PAINT MONO (-3250 5875);
DISPLAY INVISIBLE (-3250 5875);
FORCEPROP 1 LAST BODY_TYPE PLUMBING
J 0
(-3250 5925);
DISPLAY 0.872340 (-3250 5925);
PAINT GREEN (-3250 5925);
DISPLAY INVISIBLE (-3250 5925);
FORCEPROP 1 LAST HDL_TAP TRUE
J 0
(-2925 5750);
DISPLAY 0.872340 (-2925 5750);
DISPLAY INVISIBLE (-2925 5750);
FORCEPROP 1 LAST PATH I166
J 0
(-3252 5875);
DISPLAY 0.872340 (-3252 5875);
PAINT GREEN (-3252 5875);
DISPLAY INVISIBLE (-3252 5875);
FORCEADD TAP..1
(-3250 5675);
FORCEPROP 3 LASTPIN (-3300 5675) SIG_NAME M_I_CPU0_SA_DQ<6>
J 0
(-3290 5685);
DISPLAY 0.659574 (-3290 5685);
PAINT MONO (-3290 5685);
DISPLAY INVISIBLE (-3290 5685);
FORCEPROP 1 LASTPIN (-3300 5675) BN 6
J 0
(-3312 5683);
DISPLAY 0.489362 (-3312 5683);
PAINT GREEN (-3312 5683);
FORCEPROP 2 LAST CDS_LIB mstr_standard
J 0
(-3250 5675);
DISPLAY 0.723404 (-3250 5675);
PAINT MONO (-3250 5675);
DISPLAY INVISIBLE (-3250 5675);
FORCEPROP 1 LAST BODY_TYPE PLUMBING
J 0
(-3250 5725);
DISPLAY 0.872340 (-3250 5725);
PAINT GREEN (-3250 5725);
DISPLAY INVISIBLE (-3250 5725);
FORCEPROP 1 LAST HDL_TAP TRUE
J 0
(-2925 5550);
DISPLAY 0.872340 (-2925 5550);
DISPLAY INVISIBLE (-2925 5550);
FORCEPROP 1 LAST PATH I167
J 0
(-3252 5675);
DISPLAY 0.872340 (-3252 5675);
PAINT GREEN (-3252 5675);
DISPLAY INVISIBLE (-3252 5675);
FORCEADD TAP..1
(-3250 5725);
FORCEPROP 3 LASTPIN (-3300 5725) SIG_NAME M_I_CPU0_SA_DQ<5>
J 0
(-3290 5735);
DISPLAY 0.659574 (-3290 5735);
PAINT MONO (-3290 5735);
DISPLAY INVISIBLE (-3290 5735);
FORCEPROP 1 LASTPIN (-3300 5725) BN 5
J 0
(-3312 5733);
DISPLAY 0.489362 (-3312 5733);
PAINT GREEN (-3312 5733);
FORCEPROP 2 LAST CDS_LIB mstr_standard
J 0
(-3250 5725);
DISPLAY 0.723404 (-3250 5725);
PAINT MONO (-3250 5725);
DISPLAY INVISIBLE (-3250 5725);
FORCEPROP 1 LAST BODY_TYPE PLUMBING
J 0
(-3250 5775);
DISPLAY 0.872340 (-3250 5775);
PAINT GREEN (-3250 5775);
DISPLAY INVISIBLE (-3250 5775);
FORCEPROP 1 LAST HDL_TAP TRUE
J 0
(-2925 5600);
DISPLAY 0.872340 (-2925 5600);
DISPLAY INVISIBLE (-2925 5600);
FORCEPROP 1 LAST PATH I168
J 0
(-3252 5725);
DISPLAY 0.872340 (-3252 5725);
PAINT GREEN (-3252 5725);
DISPLAY INVISIBLE (-3252 5725);
FORCEADD TAP..1
(-3250 5525);
FORCEPROP 3 LASTPIN (-3300 5525) SIG_NAME M_I_CPU0_SA_DQ<8>
J 0
(-3290 5535);
DISPLAY 0.659574 (-3290 5535);
PAINT MONO (-3290 5535);
DISPLAY INVISIBLE (-3290 5535);
FORCEPROP 1 LASTPIN (-3300 5525) BN 8
J 0
(-3312 5533);
DISPLAY 0.489362 (-3312 5533);
PAINT GREEN (-3312 5533);
FORCEPROP 2 LAST CDS_LIB mstr_standard
J 0
(-3250 5525);
DISPLAY 0.723404 (-3250 5525);
PAINT MONO (-3250 5525);
DISPLAY INVISIBLE (-3250 5525);
FORCEPROP 1 LAST BODY_TYPE PLUMBING
J 0
(-3250 5575);
DISPLAY 0.872340 (-3250 5575);
PAINT GREEN (-3250 5575);
DISPLAY INVISIBLE (-3250 5575);
FORCEPROP 1 LAST HDL_TAP TRUE
J 0
(-2925 5400);
DISPLAY 0.872340 (-2925 5400);
DISPLAY INVISIBLE (-2925 5400);
FORCEPROP 1 LAST PATH I169
J 0
(-3252 5525);
DISPLAY 0.872340 (-3252 5525);
PAINT GREEN (-3252 5525);
DISPLAY INVISIBLE (-3252 5525);
FORCEADD TAP..1
(-3250 5625);
FORCEPROP 3 LASTPIN (-3300 5625) SIG_NAME M_I_CPU0_SA_DQ<7>
J 0
(-3290 5635);
DISPLAY 0.659574 (-3290 5635);
PAINT MONO (-3290 5635);
DISPLAY INVISIBLE (-3290 5635);
FORCEPROP 1 LASTPIN (-3300 5625) BN 7
J 0
(-3312 5633);
DISPLAY 0.489362 (-3312 5633);
PAINT GREEN (-3312 5633);
FORCEPROP 2 LAST CDS_LIB mstr_standard
J 0
(-3250 5625);
DISPLAY 0.723404 (-3250 5625);
PAINT MONO (-3250 5625);
DISPLAY INVISIBLE (-3250 5625);
FORCEPROP 1 LAST BODY_TYPE PLUMBING
J 0
(-3250 5675);
DISPLAY 0.872340 (-3250 5675);
PAINT GREEN (-3250 5675);
DISPLAY INVISIBLE (-3250 5675);
FORCEPROP 1 LAST HDL_TAP TRUE
J 0
(-2925 5500);
DISPLAY 0.872340 (-2925 5500);
DISPLAY INVISIBLE (-2925 5500);
FORCEPROP 1 LAST PATH I170
J 0
(-3252 5625);
DISPLAY 0.872340 (-3252 5625);
PAINT GREEN (-3252 5625);
DISPLAY INVISIBLE (-3252 5625);
FORCEADD TAP..1
(-3250 5425);
FORCEPROP 3 LASTPIN (-3300 5425) SIG_NAME M_I_CPU0_SA_DQ<10>
J 0
(-3290 5435);
DISPLAY 0.659574 (-3290 5435);
PAINT MONO (-3290 5435);
DISPLAY INVISIBLE (-3290 5435);
FORCEPROP 1 LASTPIN (-3300 5425) BN 10
J 0
(-3312 5433);
DISPLAY 0.489362 (-3312 5433);
PAINT GREEN (-3312 5433);
FORCEPROP 2 LAST CDS_LIB mstr_standard
J 0
(-3250 5425);
DISPLAY 0.723404 (-3250 5425);
PAINT MONO (-3250 5425);
DISPLAY INVISIBLE (-3250 5425);
FORCEPROP 1 LAST BODY_TYPE PLUMBING
J 0
(-3250 5475);
DISPLAY 0.872340 (-3250 5475);
PAINT GREEN (-3250 5475);
DISPLAY INVISIBLE (-3250 5475);
FORCEPROP 1 LAST HDL_TAP TRUE
J 0
(-2925 5300);
DISPLAY 0.872340 (-2925 5300);
DISPLAY INVISIBLE (-2925 5300);
FORCEPROP 1 LAST PATH I171
J 0
(-3252 5425);
DISPLAY 0.872340 (-3252 5425);
PAINT GREEN (-3252 5425);
DISPLAY INVISIBLE (-3252 5425);
FORCEADD TAP..1
(-3250 5475);
FORCEPROP 3 LASTPIN (-3300 5475) SIG_NAME M_I_CPU0_SA_DQ<9>
J 0
(-3290 5485);
DISPLAY 0.659574 (-3290 5485);
PAINT MONO (-3290 5485);
DISPLAY INVISIBLE (-3290 5485);
FORCEPROP 1 LASTPIN (-3300 5475) BN 9
J 0
(-3312 5483);
DISPLAY 0.489362 (-3312 5483);
PAINT GREEN (-3312 5483);
FORCEPROP 2 LAST CDS_LIB mstr_standard
J 0
(-3250 5475);
DISPLAY 0.723404 (-3250 5475);
PAINT MONO (-3250 5475);
DISPLAY INVISIBLE (-3250 5475);
FORCEPROP 1 LAST BODY_TYPE PLUMBING
J 0
(-3250 5525);
DISPLAY 0.872340 (-3250 5525);
PAINT GREEN (-3250 5525);
DISPLAY INVISIBLE (-3250 5525);
FORCEPROP 1 LAST HDL_TAP TRUE
J 0
(-2925 5350);
DISPLAY 0.872340 (-2925 5350);
DISPLAY INVISIBLE (-2925 5350);
FORCEPROP 1 LAST PATH I172
J 0
(-3252 5475);
DISPLAY 0.872340 (-3252 5475);
PAINT GREEN (-3252 5475);
DISPLAY INVISIBLE (-3252 5475);
FORCEADD TAP..1
(-3250 5275);
FORCEPROP 3 LASTPIN (-3300 5275) SIG_NAME M_I_CPU0_SA_DQ<13>
J 0
(-3290 5285);
DISPLAY 0.659574 (-3290 5285);
PAINT MONO (-3290 5285);
DISPLAY INVISIBLE (-3290 5285);
FORCEPROP 1 LASTPIN (-3300 5275) BN 13
J 0
(-3312 5283);
DISPLAY 0.489362 (-3312 5283);
PAINT GREEN (-3312 5283);
FORCEPROP 2 LAST CDS_LIB mstr_standard
J 0
(-3250 5275);
DISPLAY 0.723404 (-3250 5275);
PAINT MONO (-3250 5275);
DISPLAY INVISIBLE (-3250 5275);
FORCEPROP 1 LAST BODY_TYPE PLUMBING
J 0
(-3250 5325);
DISPLAY 0.872340 (-3250 5325);
PAINT GREEN (-3250 5325);
DISPLAY INVISIBLE (-3250 5325);
FORCEPROP 1 LAST HDL_TAP TRUE
J 0
(-2925 5150);
DISPLAY 0.872340 (-2925 5150);
DISPLAY INVISIBLE (-2925 5150);
FORCEPROP 1 LAST PATH I173
J 0
(-3252 5275);
DISPLAY 0.872340 (-3252 5275);
PAINT GREEN (-3252 5275);
DISPLAY INVISIBLE (-3252 5275);
FORCEADD TAP..1
(-3250 5325);
FORCEPROP 3 LASTPIN (-3300 5325) SIG_NAME M_I_CPU0_SA_DQ<12>
J 0
(-3290 5335);
DISPLAY 0.659574 (-3290 5335);
PAINT MONO (-3290 5335);
DISPLAY INVISIBLE (-3290 5335);
FORCEPROP 1 LASTPIN (-3300 5325) BN 12
J 0
(-3312 5333);
DISPLAY 0.489362 (-3312 5333);
PAINT GREEN (-3312 5333);
FORCEPROP 2 LAST CDS_LIB mstr_standard
J 0
(-3250 5325);
DISPLAY 0.723404 (-3250 5325);
PAINT MONO (-3250 5325);
DISPLAY INVISIBLE (-3250 5325);
FORCEPROP 1 LAST BODY_TYPE PLUMBING
J 0
(-3250 5375);
DISPLAY 0.872340 (-3250 5375);
PAINT GREEN (-3250 5375);
DISPLAY INVISIBLE (-3250 5375);
FORCEPROP 1 LAST HDL_TAP TRUE
J 0
(-2925 5200);
DISPLAY 0.872340 (-2925 5200);
DISPLAY INVISIBLE (-2925 5200);
FORCEPROP 1 LAST PATH I174
J 0
(-3252 5325);
DISPLAY 0.872340 (-3252 5325);
PAINT GREEN (-3252 5325);
DISPLAY INVISIBLE (-3252 5325);
FORCEADD TAP..1
(-3250 5375);
FORCEPROP 3 LASTPIN (-3300 5375) SIG_NAME M_I_CPU0_SA_DQ<11>
J 0
(-3290 5385);
DISPLAY 0.659574 (-3290 5385);
PAINT MONO (-3290 5385);
DISPLAY INVISIBLE (-3290 5385);
FORCEPROP 1 LASTPIN (-3300 5375) BN 11
J 0
(-3312 5383);
DISPLAY 0.489362 (-3312 5383);
PAINT GREEN (-3312 5383);
FORCEPROP 2 LAST CDS_LIB mstr_standard
J 0
(-3250 5375);
DISPLAY 0.723404 (-3250 5375);
PAINT MONO (-3250 5375);
DISPLAY INVISIBLE (-3250 5375);
FORCEPROP 1 LAST BODY_TYPE PLUMBING
J 0
(-3250 5425);
DISPLAY 0.872340 (-3250 5425);
PAINT GREEN (-3250 5425);
DISPLAY INVISIBLE (-3250 5425);
FORCEPROP 1 LAST HDL_TAP TRUE
J 0
(-2925 5250);
DISPLAY 0.872340 (-2925 5250);
DISPLAY INVISIBLE (-2925 5250);
FORCEPROP 1 LAST PATH I175
J 0
(-3252 5375);
DISPLAY 0.872340 (-3252 5375);
PAINT GREEN (-3252 5375);
DISPLAY INVISIBLE (-3252 5375);
FORCEADD TAP..1
(-3250 5225);
FORCEPROP 3 LASTPIN (-3300 5225) SIG_NAME M_I_CPU0_SA_DQ<14>
J 0
(-3290 5235);
DISPLAY 0.659574 (-3290 5235);
PAINT MONO (-3290 5235);
DISPLAY INVISIBLE (-3290 5235);
FORCEPROP 1 LASTPIN (-3300 5225) BN 14
J 0
(-3312 5233);
DISPLAY 0.489362 (-3312 5233);
PAINT GREEN (-3312 5233);
FORCEPROP 2 LAST CDS_LIB mstr_standard
J 0
(-3250 5225);
DISPLAY 0.723404 (-3250 5225);
PAINT MONO (-3250 5225);
DISPLAY INVISIBLE (-3250 5225);
FORCEPROP 1 LAST BODY_TYPE PLUMBING
J 0
(-3250 5275);
DISPLAY 0.872340 (-3250 5275);
PAINT GREEN (-3250 5275);
DISPLAY INVISIBLE (-3250 5275);
FORCEPROP 1 LAST HDL_TAP TRUE
J 0
(-2925 5100);
DISPLAY 0.872340 (-2925 5100);
DISPLAY INVISIBLE (-2925 5100);
FORCEPROP 1 LAST PATH I176
J 0
(-3252 5225);
DISPLAY 0.872340 (-3252 5225);
PAINT GREEN (-3252 5225);
DISPLAY INVISIBLE (-3252 5225);
FORCEADD TAP..1
(-3250 5175);
FORCEPROP 3 LASTPIN (-3300 5175) SIG_NAME M_I_CPU0_SA_DQ<15>
J 0
(-3290 5185);
DISPLAY 0.659574 (-3290 5185);
PAINT MONO (-3290 5185);
DISPLAY INVISIBLE (-3290 5185);
FORCEPROP 1 LASTPIN (-3300 5175) BN 15
J 0
(-3312 5183);
DISPLAY 0.489362 (-3312 5183);
PAINT GREEN (-3312 5183);
FORCEPROP 2 LAST CDS_LIB mstr_standard
J 0
(-3250 5175);
DISPLAY 0.723404 (-3250 5175);
PAINT MONO (-3250 5175);
DISPLAY INVISIBLE (-3250 5175);
FORCEPROP 1 LAST BODY_TYPE PLUMBING
J 0
(-3250 5225);
DISPLAY 0.872340 (-3250 5225);
PAINT GREEN (-3250 5225);
DISPLAY INVISIBLE (-3250 5225);
FORCEPROP 1 LAST HDL_TAP TRUE
J 0
(-2925 5050);
DISPLAY 0.872340 (-2925 5050);
DISPLAY INVISIBLE (-2925 5050);
FORCEPROP 1 LAST PATH I177
J 0
(-3252 5175);
DISPLAY 0.872340 (-3252 5175);
PAINT GREEN (-3252 5175);
DISPLAY INVISIBLE (-3252 5175);
FORCEADD TAP..1
(-3250 5075);
FORCEPROP 3 LASTPIN (-3300 5075) SIG_NAME M_I_CPU0_SA_DQ<16>
J 0
(-3290 5085);
DISPLAY 0.659574 (-3290 5085);
PAINT MONO (-3290 5085);
DISPLAY INVISIBLE (-3290 5085);
FORCEPROP 1 LASTPIN (-3300 5075) BN 16
J 0
(-3312 5083);
DISPLAY 0.489362 (-3312 5083);
PAINT GREEN (-3312 5083);
FORCEPROP 2 LAST CDS_LIB mstr_standard
J 0
(-3250 5075);
DISPLAY 0.723404 (-3250 5075);
PAINT MONO (-3250 5075);
DISPLAY INVISIBLE (-3250 5075);
FORCEPROP 1 LAST BODY_TYPE PLUMBING
J 0
(-3250 5125);
DISPLAY 0.872340 (-3250 5125);
PAINT GREEN (-3250 5125);
DISPLAY INVISIBLE (-3250 5125);
FORCEPROP 1 LAST HDL_TAP TRUE
J 0
(-2925 4950);
DISPLAY 0.872340 (-2925 4950);
DISPLAY INVISIBLE (-2925 4950);
FORCEPROP 1 LAST PATH I178
J 0
(-3252 5075);
DISPLAY 0.872340 (-3252 5075);
PAINT GREEN (-3252 5075);
DISPLAY INVISIBLE (-3252 5075);
FORCEADD TAP..1
(-3250 5025);
FORCEPROP 3 LASTPIN (-3300 5025) SIG_NAME M_I_CPU0_SA_DQ<17>
J 0
(-3290 5035);
DISPLAY 0.659574 (-3290 5035);
PAINT MONO (-3290 5035);
DISPLAY INVISIBLE (-3290 5035);
FORCEPROP 1 LASTPIN (-3300 5025) BN 17
J 0
(-3312 5033);
DISPLAY 0.489362 (-3312 5033);
PAINT GREEN (-3312 5033);
FORCEPROP 2 LAST CDS_LIB mstr_standard
J 0
(-3250 5025);
DISPLAY 0.723404 (-3250 5025);
PAINT MONO (-3250 5025);
DISPLAY INVISIBLE (-3250 5025);
FORCEPROP 1 LAST BODY_TYPE PLUMBING
J 0
(-3250 5075);
DISPLAY 0.872340 (-3250 5075);
PAINT GREEN (-3250 5075);
DISPLAY INVISIBLE (-3250 5075);
FORCEPROP 1 LAST HDL_TAP TRUE
J 0
(-2925 4900);
DISPLAY 0.872340 (-2925 4900);
DISPLAY INVISIBLE (-2925 4900);
FORCEPROP 1 LAST PATH I179
J 0
(-3252 5025);
DISPLAY 0.872340 (-3252 5025);
PAINT GREEN (-3252 5025);
DISPLAY INVISIBLE (-3252 5025);
FORCEADD TAP..1
(-3250 4875);
FORCEPROP 3 LASTPIN (-3300 4875) SIG_NAME M_I_CPU0_SA_DQ<20>
J 0
(-3290 4885);
DISPLAY 0.659574 (-3290 4885);
PAINT MONO (-3290 4885);
DISPLAY INVISIBLE (-3290 4885);
FORCEPROP 1 LASTPIN (-3300 4875) BN 20
J 0
(-3312 4883);
DISPLAY 0.489362 (-3312 4883);
PAINT GREEN (-3312 4883);
FORCEPROP 2 LAST CDS_LIB mstr_standard
J 0
(-3250 4875);
DISPLAY 0.723404 (-3250 4875);
PAINT MONO (-3250 4875);
DISPLAY INVISIBLE (-3250 4875);
FORCEPROP 1 LAST BODY_TYPE PLUMBING
J 0
(-3250 4925);
DISPLAY 0.872340 (-3250 4925);
PAINT GREEN (-3250 4925);
DISPLAY INVISIBLE (-3250 4925);
FORCEPROP 1 LAST HDL_TAP TRUE
J 0
(-2925 4750);
DISPLAY 0.872340 (-2925 4750);
DISPLAY INVISIBLE (-2925 4750);
FORCEPROP 1 LAST PATH I180
J 0
(-3252 4875);
DISPLAY 0.872340 (-3252 4875);
PAINT GREEN (-3252 4875);
DISPLAY INVISIBLE (-3252 4875);
FORCEADD TAP..1
(-3250 4925);
FORCEPROP 3 LASTPIN (-3300 4925) SIG_NAME M_I_CPU0_SA_DQ<19>
J 0
(-3290 4935);
DISPLAY 0.659574 (-3290 4935);
PAINT MONO (-3290 4935);
DISPLAY INVISIBLE (-3290 4935);
FORCEPROP 1 LASTPIN (-3300 4925) BN 19
J 0
(-3312 4933);
DISPLAY 0.489362 (-3312 4933);
PAINT GREEN (-3312 4933);
FORCEPROP 2 LAST CDS_LIB mstr_standard
J 0
(-3250 4925);
DISPLAY 0.723404 (-3250 4925);
PAINT MONO (-3250 4925);
DISPLAY INVISIBLE (-3250 4925);
FORCEPROP 1 LAST BODY_TYPE PLUMBING
J 0
(-3250 4975);
DISPLAY 0.872340 (-3250 4975);
PAINT GREEN (-3250 4975);
DISPLAY INVISIBLE (-3250 4975);
FORCEPROP 1 LAST HDL_TAP TRUE
J 0
(-2925 4800);
DISPLAY 0.872340 (-2925 4800);
DISPLAY INVISIBLE (-2925 4800);
FORCEPROP 1 LAST PATH I181
J 0
(-3252 4925);
DISPLAY 0.872340 (-3252 4925);
PAINT GREEN (-3252 4925);
DISPLAY INVISIBLE (-3252 4925);
FORCEADD TAP..1
(-3250 4975);
FORCEPROP 3 LASTPIN (-3300 4975) SIG_NAME M_I_CPU0_SA_DQ<18>
J 0
(-3290 4985);
DISPLAY 0.659574 (-3290 4985);
PAINT MONO (-3290 4985);
DISPLAY INVISIBLE (-3290 4985);
FORCEPROP 1 LASTPIN (-3300 4975) BN 18
J 0
(-3312 4983);
DISPLAY 0.489362 (-3312 4983);
PAINT GREEN (-3312 4983);
FORCEPROP 2 LAST CDS_LIB mstr_standard
J 0
(-3250 4975);
DISPLAY 0.723404 (-3250 4975);
PAINT MONO (-3250 4975);
DISPLAY INVISIBLE (-3250 4975);
FORCEPROP 1 LAST BODY_TYPE PLUMBING
J 0
(-3250 5025);
DISPLAY 0.872340 (-3250 5025);
PAINT GREEN (-3250 5025);
DISPLAY INVISIBLE (-3250 5025);
FORCEPROP 1 LAST HDL_TAP TRUE
J 0
(-2925 4850);
DISPLAY 0.872340 (-2925 4850);
DISPLAY INVISIBLE (-2925 4850);
FORCEPROP 1 LAST PATH I182
J 0
(-3252 4975);
DISPLAY 0.872340 (-3252 4975);
PAINT GREEN (-3252 4975);
DISPLAY INVISIBLE (-3252 4975);
FORCEADD TAP..1
(-3250 4775);
FORCEPROP 3 LASTPIN (-3300 4775) SIG_NAME M_I_CPU0_SA_DQ<22>
J 0
(-3290 4785);
DISPLAY 0.659574 (-3290 4785);
PAINT MONO (-3290 4785);
DISPLAY INVISIBLE (-3290 4785);
FORCEPROP 1 LASTPIN (-3300 4775) BN 22
J 0
(-3312 4783);
DISPLAY 0.489362 (-3312 4783);
PAINT GREEN (-3312 4783);
FORCEPROP 2 LAST CDS_LIB mstr_standard
J 0
(-3250 4775);
DISPLAY 0.723404 (-3250 4775);
PAINT MONO (-3250 4775);
DISPLAY INVISIBLE (-3250 4775);
FORCEPROP 1 LAST BODY_TYPE PLUMBING
J 0
(-3250 4825);
DISPLAY 0.872340 (-3250 4825);
PAINT GREEN (-3250 4825);
DISPLAY INVISIBLE (-3250 4825);
FORCEPROP 1 LAST HDL_TAP TRUE
J 0
(-2925 4650);
DISPLAY 0.872340 (-2925 4650);
DISPLAY INVISIBLE (-2925 4650);
FORCEPROP 1 LAST PATH I183
J 0
(-3252 4775);
DISPLAY 0.872340 (-3252 4775);
PAINT GREEN (-3252 4775);
DISPLAY INVISIBLE (-3252 4775);
FORCEADD TAP..1
(-3250 4825);
FORCEPROP 3 LASTPIN (-3300 4825) SIG_NAME M_I_CPU0_SA_DQ<21>
J 0
(-3290 4835);
DISPLAY 0.659574 (-3290 4835);
PAINT MONO (-3290 4835);
DISPLAY INVISIBLE (-3290 4835);
FORCEPROP 1 LASTPIN (-3300 4825) BN 21
J 0
(-3312 4833);
DISPLAY 0.489362 (-3312 4833);
PAINT GREEN (-3312 4833);
FORCEPROP 2 LAST CDS_LIB mstr_standard
J 0
(-3250 4825);
DISPLAY 0.723404 (-3250 4825);
PAINT MONO (-3250 4825);
DISPLAY INVISIBLE (-3250 4825);
FORCEPROP 1 LAST BODY_TYPE PLUMBING
J 0
(-3250 4875);
DISPLAY 0.872340 (-3250 4875);
PAINT GREEN (-3250 4875);
DISPLAY INVISIBLE (-3250 4875);
FORCEPROP 1 LAST HDL_TAP TRUE
J 0
(-2925 4700);
DISPLAY 0.872340 (-2925 4700);
DISPLAY INVISIBLE (-2925 4700);
FORCEPROP 1 LAST PATH I184
J 0
(-3252 4825);
DISPLAY 0.872340 (-3252 4825);
PAINT GREEN (-3252 4825);
DISPLAY INVISIBLE (-3252 4825);
FORCEADD TAP..1
(-3250 4725);
FORCEPROP 3 LASTPIN (-3300 4725) SIG_NAME M_I_CPU0_SA_DQ<23>
J 0
(-3290 4735);
DISPLAY 0.659574 (-3290 4735);
PAINT MONO (-3290 4735);
DISPLAY INVISIBLE (-3290 4735);
FORCEPROP 1 LASTPIN (-3300 4725) BN 23
J 0
(-3312 4733);
DISPLAY 0.489362 (-3312 4733);
PAINT GREEN (-3312 4733);
FORCEPROP 2 LAST CDS_LIB mstr_standard
J 0
(-3250 4725);
DISPLAY 0.723404 (-3250 4725);
PAINT MONO (-3250 4725);
DISPLAY INVISIBLE (-3250 4725);
FORCEPROP 1 LAST BODY_TYPE PLUMBING
J 0
(-3250 4775);
DISPLAY 0.872340 (-3250 4775);
PAINT GREEN (-3250 4775);
DISPLAY INVISIBLE (-3250 4775);
FORCEPROP 1 LAST HDL_TAP TRUE
J 0
(-2925 4600);
DISPLAY 0.872340 (-2925 4600);
DISPLAY INVISIBLE (-2925 4600);
FORCEPROP 1 LAST PATH I185
J 0
(-3252 4725);
DISPLAY 0.872340 (-3252 4725);
PAINT GREEN (-3252 4725);
DISPLAY INVISIBLE (-3252 4725);
FORCEADD TAP..1
(-3250 4625);
FORCEPROP 3 LASTPIN (-3300 4625) SIG_NAME M_I_CPU0_SA_DQ<24>
J 0
(-3290 4635);
DISPLAY 0.659574 (-3290 4635);
PAINT MONO (-3290 4635);
DISPLAY INVISIBLE (-3290 4635);
FORCEPROP 1 LASTPIN (-3300 4625) BN 24
J 0
(-3312 4633);
DISPLAY 0.489362 (-3312 4633);
PAINT GREEN (-3312 4633);
FORCEPROP 2 LAST CDS_LIB mstr_standard
J 0
(-3250 4625);
DISPLAY 0.723404 (-3250 4625);
PAINT MONO (-3250 4625);
DISPLAY INVISIBLE (-3250 4625);
FORCEPROP 1 LAST BODY_TYPE PLUMBING
J 0
(-3250 4675);
DISPLAY 0.872340 (-3250 4675);
PAINT GREEN (-3250 4675);
DISPLAY INVISIBLE (-3250 4675);
FORCEPROP 1 LAST HDL_TAP TRUE
J 0
(-2925 4500);
DISPLAY 0.872340 (-2925 4500);
DISPLAY INVISIBLE (-2925 4500);
FORCEPROP 1 LAST PATH I186
J 0
(-3252 4625);
DISPLAY 0.872340 (-3252 4625);
PAINT GREEN (-3252 4625);
DISPLAY INVISIBLE (-3252 4625);
FORCEADD TAP..1
(-3250 4525);
FORCEPROP 3 LASTPIN (-3300 4525) SIG_NAME M_I_CPU0_SA_DQ<26>
J 0
(-3290 4535);
DISPLAY 0.659574 (-3290 4535);
PAINT MONO (-3290 4535);
DISPLAY INVISIBLE (-3290 4535);
FORCEPROP 1 LASTPIN (-3300 4525) BN 26
J 0
(-3312 4533);
DISPLAY 0.489362 (-3312 4533);
PAINT GREEN (-3312 4533);
FORCEPROP 2 LAST CDS_LIB mstr_standard
J 0
(-3250 4525);
DISPLAY 0.723404 (-3250 4525);
PAINT MONO (-3250 4525);
DISPLAY INVISIBLE (-3250 4525);
FORCEPROP 1 LAST BODY_TYPE PLUMBING
J 0
(-3250 4575);
DISPLAY 0.872340 (-3250 4575);
PAINT GREEN (-3250 4575);
DISPLAY INVISIBLE (-3250 4575);
FORCEPROP 1 LAST HDL_TAP TRUE
J 0
(-2925 4400);
DISPLAY 0.872340 (-2925 4400);
DISPLAY INVISIBLE (-2925 4400);
FORCEPROP 1 LAST PATH I187
J 0
(-3252 4525);
DISPLAY 0.872340 (-3252 4525);
PAINT GREEN (-3252 4525);
DISPLAY INVISIBLE (-3252 4525);
FORCEADD TAP..1
(-3250 4575);
FORCEPROP 3 LASTPIN (-3300 4575) SIG_NAME M_I_CPU0_SA_DQ<25>
J 0
(-3290 4585);
DISPLAY 0.659574 (-3290 4585);
PAINT MONO (-3290 4585);
DISPLAY INVISIBLE (-3290 4585);
FORCEPROP 1 LASTPIN (-3300 4575) BN 25
J 0
(-3312 4583);
DISPLAY 0.489362 (-3312 4583);
PAINT GREEN (-3312 4583);
FORCEPROP 2 LAST CDS_LIB mstr_standard
J 0
(-3250 4575);
DISPLAY 0.723404 (-3250 4575);
PAINT MONO (-3250 4575);
DISPLAY INVISIBLE (-3250 4575);
FORCEPROP 1 LAST BODY_TYPE PLUMBING
J 0
(-3250 4625);
DISPLAY 0.872340 (-3250 4625);
PAINT GREEN (-3250 4625);
DISPLAY INVISIBLE (-3250 4625);
FORCEPROP 1 LAST HDL_TAP TRUE
J 0
(-2925 4450);
DISPLAY 0.872340 (-2925 4450);
DISPLAY INVISIBLE (-2925 4450);
FORCEPROP 1 LAST PATH I188
J 0
(-3252 4575);
DISPLAY 0.872340 (-3252 4575);
PAINT GREEN (-3252 4575);
DISPLAY INVISIBLE (-3252 4575);
FORCEADD TAP..1
(-3250 4375);
FORCEPROP 3 LASTPIN (-3300 4375) SIG_NAME M_I_CPU0_SA_DQ<29>
J 0
(-3290 4385);
DISPLAY 0.659574 (-3290 4385);
PAINT MONO (-3290 4385);
DISPLAY INVISIBLE (-3290 4385);
FORCEPROP 1 LASTPIN (-3300 4375) BN 29
J 0
(-3312 4383);
DISPLAY 0.489362 (-3312 4383);
PAINT GREEN (-3312 4383);
FORCEPROP 2 LAST CDS_LIB mstr_standard
J 0
(-3250 4375);
DISPLAY 0.723404 (-3250 4375);
PAINT MONO (-3250 4375);
DISPLAY INVISIBLE (-3250 4375);
FORCEPROP 1 LAST BODY_TYPE PLUMBING
J 0
(-3250 4425);
DISPLAY 0.872340 (-3250 4425);
PAINT GREEN (-3250 4425);
DISPLAY INVISIBLE (-3250 4425);
FORCEPROP 1 LAST HDL_TAP TRUE
J 0
(-2925 4250);
DISPLAY 0.872340 (-2925 4250);
DISPLAY INVISIBLE (-2925 4250);
FORCEPROP 1 LAST PATH I189
J 0
(-3252 4375);
DISPLAY 0.872340 (-3252 4375);
PAINT GREEN (-3252 4375);
DISPLAY INVISIBLE (-3252 4375);
FORCEADD TAP..1
(-3250 4425);
FORCEPROP 3 LASTPIN (-3300 4425) SIG_NAME M_I_CPU0_SA_DQ<28>
J 0
(-3290 4435);
DISPLAY 0.659574 (-3290 4435);
PAINT MONO (-3290 4435);
DISPLAY INVISIBLE (-3290 4435);
FORCEPROP 1 LASTPIN (-3300 4425) BN 28
J 0
(-3312 4433);
DISPLAY 0.489362 (-3312 4433);
PAINT GREEN (-3312 4433);
FORCEPROP 2 LAST CDS_LIB mstr_standard
J 0
(-3250 4425);
DISPLAY 0.723404 (-3250 4425);
PAINT MONO (-3250 4425);
DISPLAY INVISIBLE (-3250 4425);
FORCEPROP 1 LAST BODY_TYPE PLUMBING
J 0
(-3250 4475);
DISPLAY 0.872340 (-3250 4475);
PAINT GREEN (-3250 4475);
DISPLAY INVISIBLE (-3250 4475);
FORCEPROP 1 LAST HDL_TAP TRUE
J 0
(-2925 4300);
DISPLAY 0.872340 (-2925 4300);
DISPLAY INVISIBLE (-2925 4300);
FORCEPROP 1 LAST PATH I190
J 0
(-3252 4425);
DISPLAY 0.872340 (-3252 4425);
PAINT GREEN (-3252 4425);
DISPLAY INVISIBLE (-3252 4425);
FORCEADD TAP..1
(-3250 4475);
FORCEPROP 3 LASTPIN (-3300 4475) SIG_NAME M_I_CPU0_SA_DQ<27>
J 0
(-3290 4485);
DISPLAY 0.659574 (-3290 4485);
PAINT MONO (-3290 4485);
DISPLAY INVISIBLE (-3290 4485);
FORCEPROP 1 LASTPIN (-3300 4475) BN 27
J 0
(-3312 4483);
DISPLAY 0.489362 (-3312 4483);
PAINT GREEN (-3312 4483);
FORCEPROP 2 LAST CDS_LIB mstr_standard
J 0
(-3250 4475);
DISPLAY 0.723404 (-3250 4475);
PAINT MONO (-3250 4475);
DISPLAY INVISIBLE (-3250 4475);
FORCEPROP 1 LAST BODY_TYPE PLUMBING
J 0
(-3250 4525);
DISPLAY 0.872340 (-3250 4525);
PAINT GREEN (-3250 4525);
DISPLAY INVISIBLE (-3250 4525);
FORCEPROP 1 LAST HDL_TAP TRUE
J 0
(-2925 4350);
DISPLAY 0.872340 (-2925 4350);
DISPLAY INVISIBLE (-2925 4350);
FORCEPROP 1 LAST PATH I191
J 0
(-3252 4475);
DISPLAY 0.872340 (-3252 4475);
PAINT GREEN (-3252 4475);
DISPLAY INVISIBLE (-3252 4475);
FORCEADD TAP..1
(-3250 4325);
FORCEPROP 3 LASTPIN (-3300 4325) SIG_NAME M_I_CPU0_SA_DQ<30>
J 0
(-3290 4335);
DISPLAY 0.659574 (-3290 4335);
PAINT MONO (-3290 4335);
DISPLAY INVISIBLE (-3290 4335);
FORCEPROP 1 LASTPIN (-3300 4325) BN 30
J 0
(-3312 4333);
DISPLAY 0.489362 (-3312 4333);
PAINT GREEN (-3312 4333);
FORCEPROP 2 LAST CDS_LIB mstr_standard
J 0
(-3250 4325);
DISPLAY 0.723404 (-3250 4325);
PAINT MONO (-3250 4325);
DISPLAY INVISIBLE (-3250 4325);
FORCEPROP 1 LAST BODY_TYPE PLUMBING
J 0
(-3250 4375);
DISPLAY 0.872340 (-3250 4375);
PAINT GREEN (-3250 4375);
DISPLAY INVISIBLE (-3250 4375);
FORCEPROP 1 LAST HDL_TAP TRUE
J 0
(-2925 4200);
DISPLAY 0.872340 (-2925 4200);
DISPLAY INVISIBLE (-2925 4200);
FORCEPROP 1 LAST PATH I192
J 0
(-3252 4325);
DISPLAY 0.872340 (-3252 4325);
PAINT GREEN (-3252 4325);
DISPLAY INVISIBLE (-3252 4325);
FORCEADD TAP..1
(-3250 4275);
FORCEPROP 3 LASTPIN (-3300 4275) SIG_NAME M_I_CPU0_SA_DQ<31>
J 0
(-3290 4285);
DISPLAY 0.659574 (-3290 4285);
PAINT MONO (-3290 4285);
DISPLAY INVISIBLE (-3290 4285);
FORCEPROP 1 LASTPIN (-3300 4275) BN 31
J 0
(-3312 4283);
DISPLAY 0.489362 (-3312 4283);
PAINT GREEN (-3312 4283);
FORCEPROP 2 LAST CDS_LIB mstr_standard
J 0
(-3250 4275);
DISPLAY 0.723404 (-3250 4275);
PAINT MONO (-3250 4275);
DISPLAY INVISIBLE (-3250 4275);
FORCEPROP 1 LAST BODY_TYPE PLUMBING
J 0
(-3250 4325);
DISPLAY 0.872340 (-3250 4325);
PAINT GREEN (-3250 4325);
DISPLAY INVISIBLE (-3250 4325);
FORCEPROP 1 LAST HDL_TAP TRUE
J 0
(-2925 4150);
DISPLAY 0.872340 (-2925 4150);
DISPLAY INVISIBLE (-2925 4150);
FORCEPROP 1 LAST PATH I193
J 0
(-3252 4275);
DISPLAY 0.872340 (-3252 4275);
PAINT GREEN (-3252 4275);
DISPLAY INVISIBLE (-3252 4275);
FORCEADD TAP..1
(-3250 4175);
FORCEPROP 3 LASTPIN (-3300 4175) SIG_NAME M_I_CPU0_SB_DQ<0>
J 0
(-3290 4185);
DISPLAY 0.659574 (-3290 4185);
PAINT MONO (-3290 4185);
DISPLAY INVISIBLE (-3290 4185);
FORCEPROP 1 LASTPIN (-3300 4175) BN 0
J 0
(-3312 4183);
DISPLAY 0.489362 (-3312 4183);
PAINT GREEN (-3312 4183);
FORCEPROP 2 LAST CDS_LIB mstr_standard
J 0
(-3250 4175);
DISPLAY 0.723404 (-3250 4175);
PAINT MONO (-3250 4175);
DISPLAY INVISIBLE (-3250 4175);
FORCEPROP 1 LAST BODY_TYPE PLUMBING
J 0
(-3250 4225);
DISPLAY 0.872340 (-3250 4225);
PAINT GREEN (-3250 4225);
DISPLAY INVISIBLE (-3250 4225);
FORCEPROP 1 LAST HDL_TAP TRUE
J 0
(-2925 4050);
DISPLAY 0.872340 (-2925 4050);
DISPLAY INVISIBLE (-2925 4050);
FORCEPROP 1 LAST PATH I194
J 0
(-3252 4175);
DISPLAY 0.872340 (-3252 4175);
PAINT GREEN (-3252 4175);
DISPLAY INVISIBLE (-3252 4175);
FORCEADD TAP..1
(-3250 4125);
FORCEPROP 3 LASTPIN (-3300 4125) SIG_NAME M_I_CPU0_SB_DQ<1>
J 0
(-3290 4135);
DISPLAY 0.659574 (-3290 4135);
PAINT MONO (-3290 4135);
DISPLAY INVISIBLE (-3290 4135);
FORCEPROP 1 LASTPIN (-3300 4125) BN 1
J 0
(-3312 4133);
DISPLAY 0.489362 (-3312 4133);
PAINT GREEN (-3312 4133);
FORCEPROP 2 LAST CDS_LIB mstr_standard
J 0
(-3250 4125);
DISPLAY 0.723404 (-3250 4125);
PAINT MONO (-3250 4125);
DISPLAY INVISIBLE (-3250 4125);
FORCEPROP 1 LAST BODY_TYPE PLUMBING
J 0
(-3250 4175);
DISPLAY 0.872340 (-3250 4175);
PAINT GREEN (-3250 4175);
DISPLAY INVISIBLE (-3250 4175);
FORCEPROP 1 LAST HDL_TAP TRUE
J 0
(-2925 4000);
DISPLAY 0.872340 (-2925 4000);
DISPLAY INVISIBLE (-2925 4000);
FORCEPROP 1 LAST PATH I195
J 0
(-3252 4125);
DISPLAY 0.872340 (-3252 4125);
PAINT GREEN (-3252 4125);
DISPLAY INVISIBLE (-3252 4125);
FORCEADD OFFPAGE..6
R 2
(-2650 2425);
FORCEPROP 2 LAST $XR0 94 
J 0
(-2436 2425);
DISPLAY 0.638298 (-2436 2425);
PAINT MONO (-2436 2425);
FORCEPROP 2 LAST CDS_LIB mstr_standard
J 2
(-2650 2425);
DISPLAY 0.723404 (-2650 2425);
PAINT MONO (-2650 2425);
DISPLAY INVISIBLE (-2650 2425);
FORCEPROP 1 LAST OFFPAGE TRUE
J 2
(-2975 2300);
DISPLAY 0.872340 (-2975 2300);
PAINT GREEN (-2975 2300);
DISPLAY INVISIBLE (-2975 2300);
FORCEPROP 1 LAST COMMENT_BODY TRUE
J 2
(-2750 2350);
DISPLAY 0.872340 (-2750 2350);
PAINT GREEN (-2750 2350);
DISPLAY INVISIBLE (-2750 2350);
FORCEPROP 2 LAST PATH I196
J 0
(-2425 2475);
DISPLAY 1.021277 (-2425 2475);
DISPLAY INVISIBLE (-2425 2475);
FORCEADD TAP..1
(-3250 3975);
FORCEPROP 3 LASTPIN (-3300 3975) SIG_NAME M_I_CPU0_SB_DQ<4>
J 0
(-3290 3985);
DISPLAY 0.659574 (-3290 3985);
PAINT MONO (-3290 3985);
DISPLAY INVISIBLE (-3290 3985);
FORCEPROP 1 LASTPIN (-3300 3975) BN 4
J 0
(-3312 3983);
DISPLAY 0.489362 (-3312 3983);
PAINT GREEN (-3312 3983);
FORCEPROP 2 LAST CDS_LIB mstr_standard
J 0
(-3250 3975);
DISPLAY 0.723404 (-3250 3975);
PAINT MONO (-3250 3975);
DISPLAY INVISIBLE (-3250 3975);
FORCEPROP 1 LAST BODY_TYPE PLUMBING
J 0
(-3250 4025);
DISPLAY 0.872340 (-3250 4025);
PAINT GREEN (-3250 4025);
DISPLAY INVISIBLE (-3250 4025);
FORCEPROP 1 LAST HDL_TAP TRUE
J 0
(-2925 3850);
DISPLAY 0.872340 (-2925 3850);
DISPLAY INVISIBLE (-2925 3850);
FORCEPROP 1 LAST PATH I197
J 0
(-3252 3975);
DISPLAY 0.872340 (-3252 3975);
PAINT GREEN (-3252 3975);
DISPLAY INVISIBLE (-3252 3975);
FORCEADD TAP..1
(-3250 4075);
FORCEPROP 3 LASTPIN (-3300 4075) SIG_NAME M_I_CPU0_SB_DQ<2>
J 0
(-3290 4085);
DISPLAY 0.659574 (-3290 4085);
PAINT MONO (-3290 4085);
DISPLAY INVISIBLE (-3290 4085);
FORCEPROP 1 LASTPIN (-3300 4075) BN 2
J 0
(-3312 4083);
DISPLAY 0.489362 (-3312 4083);
PAINT GREEN (-3312 4083);
FORCEPROP 2 LAST CDS_LIB mstr_standard
J 0
(-3250 4075);
DISPLAY 0.723404 (-3250 4075);
PAINT MONO (-3250 4075);
DISPLAY INVISIBLE (-3250 4075);
FORCEPROP 1 LAST BODY_TYPE PLUMBING
J 0
(-3250 4125);
DISPLAY 0.872340 (-3250 4125);
PAINT GREEN (-3250 4125);
DISPLAY INVISIBLE (-3250 4125);
FORCEPROP 1 LAST HDL_TAP TRUE
J 0
(-2925 3950);
DISPLAY 0.872340 (-2925 3950);
DISPLAY INVISIBLE (-2925 3950);
FORCEPROP 1 LAST PATH I198
J 0
(-3252 4075);
DISPLAY 0.872340 (-3252 4075);
PAINT GREEN (-3252 4075);
DISPLAY INVISIBLE (-3252 4075);
FORCEADD TAP..1
(-3250 4025);
FORCEPROP 3 LASTPIN (-3300 4025) SIG_NAME M_I_CPU0_SB_DQ<3>
J 0
(-3290 4035);
DISPLAY 0.659574 (-3290 4035);
PAINT MONO (-3290 4035);
DISPLAY INVISIBLE (-3290 4035);
FORCEPROP 1 LASTPIN (-3300 4025) BN 3
J 0
(-3312 4033);
DISPLAY 0.489362 (-3312 4033);
PAINT GREEN (-3312 4033);
FORCEPROP 2 LAST CDS_LIB mstr_standard
J 0
(-3250 4025);
DISPLAY 0.723404 (-3250 4025);
PAINT MONO (-3250 4025);
DISPLAY INVISIBLE (-3250 4025);
FORCEPROP 1 LAST BODY_TYPE PLUMBING
J 0
(-3250 4075);
DISPLAY 0.872340 (-3250 4075);
PAINT GREEN (-3250 4075);
DISPLAY INVISIBLE (-3250 4075);
FORCEPROP 1 LAST HDL_TAP TRUE
J 0
(-2925 3900);
DISPLAY 0.872340 (-2925 3900);
DISPLAY INVISIBLE (-2925 3900);
FORCEPROP 1 LAST PATH I199
J 0
(-3252 4025);
DISPLAY 0.872340 (-3252 4025);
PAINT GREEN (-3252 4025);
DISPLAY INVISIBLE (-3252 4025);
FORCEADD TAP..1
(-3250 3925);
FORCEPROP 3 LASTPIN (-3300 3925) SIG_NAME M_I_CPU0_SB_DQ<5>
J 0
(-3290 3935);
DISPLAY 0.659574 (-3290 3935);
PAINT MONO (-3290 3935);
DISPLAY INVISIBLE (-3290 3935);
FORCEPROP 1 LASTPIN (-3300 3925) BN 5
J 0
(-3312 3933);
DISPLAY 0.489362 (-3312 3933);
PAINT GREEN (-3312 3933);
FORCEPROP 2 LAST CDS_LIB mstr_standard
J 0
(-3250 3925);
DISPLAY 0.723404 (-3250 3925);
PAINT MONO (-3250 3925);
DISPLAY INVISIBLE (-3250 3925);
FORCEPROP 1 LAST BODY_TYPE PLUMBING
J 0
(-3250 3975);
DISPLAY 0.872340 (-3250 3975);
PAINT GREEN (-3250 3975);
DISPLAY INVISIBLE (-3250 3975);
FORCEPROP 1 LAST HDL_TAP TRUE
J 0
(-2925 3800);
DISPLAY 0.872340 (-2925 3800);
DISPLAY INVISIBLE (-2925 3800);
FORCEPROP 1 LAST PATH I200
J 0
(-3252 3925);
DISPLAY 0.872340 (-3252 3925);
PAINT GREEN (-3252 3925);
DISPLAY INVISIBLE (-3252 3925);
FORCEADD TAP..1
(-3250 3875);
FORCEPROP 3 LASTPIN (-3300 3875) SIG_NAME M_I_CPU0_SB_DQ<6>
J 0
(-3290 3885);
DISPLAY 0.659574 (-3290 3885);
PAINT MONO (-3290 3885);
DISPLAY INVISIBLE (-3290 3885);
FORCEPROP 1 LASTPIN (-3300 3875) BN 6
J 0
(-3312 3883);
DISPLAY 0.489362 (-3312 3883);
PAINT GREEN (-3312 3883);
FORCEPROP 2 LAST CDS_LIB mstr_standard
J 0
(-3250 3875);
DISPLAY 0.723404 (-3250 3875);
PAINT MONO (-3250 3875);
DISPLAY INVISIBLE (-3250 3875);
FORCEPROP 1 LAST BODY_TYPE PLUMBING
J 0
(-3250 3925);
DISPLAY 0.872340 (-3250 3925);
PAINT GREEN (-3250 3925);
DISPLAY INVISIBLE (-3250 3925);
FORCEPROP 1 LAST HDL_TAP TRUE
J 0
(-2925 3750);
DISPLAY 0.872340 (-2925 3750);
DISPLAY INVISIBLE (-2925 3750);
FORCEPROP 1 LAST PATH I201
J 0
(-3252 3875);
DISPLAY 0.872340 (-3252 3875);
PAINT GREEN (-3252 3875);
DISPLAY INVISIBLE (-3252 3875);
FORCEADD TAP..1
(-3250 3825);
FORCEPROP 3 LASTPIN (-3300 3825) SIG_NAME M_I_CPU0_SB_DQ<7>
J 0
(-3290 3835);
DISPLAY 0.659574 (-3290 3835);
PAINT MONO (-3290 3835);
DISPLAY INVISIBLE (-3290 3835);
FORCEPROP 1 LASTPIN (-3300 3825) BN 7
J 0
(-3312 3833);
DISPLAY 0.489362 (-3312 3833);
PAINT GREEN (-3312 3833);
FORCEPROP 2 LAST CDS_LIB mstr_standard
J 0
(-3250 3825);
DISPLAY 0.723404 (-3250 3825);
PAINT MONO (-3250 3825);
DISPLAY INVISIBLE (-3250 3825);
FORCEPROP 1 LAST BODY_TYPE PLUMBING
J 0
(-3250 3875);
DISPLAY 0.872340 (-3250 3875);
PAINT GREEN (-3250 3875);
DISPLAY INVISIBLE (-3250 3875);
FORCEPROP 1 LAST HDL_TAP TRUE
J 0
(-2925 3700);
DISPLAY 0.872340 (-2925 3700);
DISPLAY INVISIBLE (-2925 3700);
FORCEPROP 1 LAST PATH I202
J 0
(-3252 3825);
DISPLAY 0.872340 (-3252 3825);
PAINT GREEN (-3252 3825);
DISPLAY INVISIBLE (-3252 3825);
FORCEADD TAP..1
(-3250 3725);
FORCEPROP 3 LASTPIN (-3300 3725) SIG_NAME M_I_CPU0_SB_DQ<8>
J 0
(-3290 3735);
DISPLAY 0.659574 (-3290 3735);
PAINT MONO (-3290 3735);
DISPLAY INVISIBLE (-3290 3735);
FORCEPROP 1 LASTPIN (-3300 3725) BN 8
J 0
(-3312 3733);
DISPLAY 0.489362 (-3312 3733);
PAINT GREEN (-3312 3733);
FORCEPROP 2 LAST CDS_LIB mstr_standard
J 0
(-3250 3725);
DISPLAY 0.723404 (-3250 3725);
PAINT MONO (-3250 3725);
DISPLAY INVISIBLE (-3250 3725);
FORCEPROP 1 LAST BODY_TYPE PLUMBING
J 0
(-3250 3775);
DISPLAY 0.872340 (-3250 3775);
PAINT GREEN (-3250 3775);
DISPLAY INVISIBLE (-3250 3775);
FORCEPROP 1 LAST HDL_TAP TRUE
J 0
(-2925 3600);
DISPLAY 0.872340 (-2925 3600);
DISPLAY INVISIBLE (-2925 3600);
FORCEPROP 1 LAST PATH I203
J 0
(-3252 3725);
DISPLAY 0.872340 (-3252 3725);
PAINT GREEN (-3252 3725);
DISPLAY INVISIBLE (-3252 3725);
FORCEADD TAP..1
(-3250 3675);
FORCEPROP 3 LASTPIN (-3300 3675) SIG_NAME M_I_CPU0_SB_DQ<9>
J 0
(-3290 3685);
DISPLAY 0.659574 (-3290 3685);
PAINT MONO (-3290 3685);
DISPLAY INVISIBLE (-3290 3685);
FORCEPROP 1 LASTPIN (-3300 3675) BN 9
J 0
(-3312 3683);
DISPLAY 0.489362 (-3312 3683);
PAINT GREEN (-3312 3683);
FORCEPROP 2 LAST CDS_LIB mstr_standard
J 0
(-3250 3675);
DISPLAY 0.723404 (-3250 3675);
PAINT MONO (-3250 3675);
DISPLAY INVISIBLE (-3250 3675);
FORCEPROP 1 LAST BODY_TYPE PLUMBING
J 0
(-3250 3725);
DISPLAY 0.872340 (-3250 3725);
PAINT GREEN (-3250 3725);
DISPLAY INVISIBLE (-3250 3725);
FORCEPROP 1 LAST HDL_TAP TRUE
J 0
(-2925 3550);
DISPLAY 0.872340 (-2925 3550);
DISPLAY INVISIBLE (-2925 3550);
FORCEPROP 1 LAST PATH I204
J 0
(-3252 3675);
DISPLAY 0.872340 (-3252 3675);
PAINT GREEN (-3252 3675);
DISPLAY INVISIBLE (-3252 3675);
FORCEADD TAP..1
(-3250 3625);
FORCEPROP 3 LASTPIN (-3300 3625) SIG_NAME M_I_CPU0_SB_DQ<10>
J 0
(-3290 3635);
DISPLAY 0.659574 (-3290 3635);
PAINT MONO (-3290 3635);
DISPLAY INVISIBLE (-3290 3635);
FORCEPROP 1 LASTPIN (-3300 3625) BN 10
J 0
(-3312 3633);
DISPLAY 0.489362 (-3312 3633);
PAINT GREEN (-3312 3633);
FORCEPROP 2 LAST CDS_LIB mstr_standard
J 0
(-3250 3625);
DISPLAY 0.723404 (-3250 3625);
PAINT MONO (-3250 3625);
DISPLAY INVISIBLE (-3250 3625);
FORCEPROP 1 LAST BODY_TYPE PLUMBING
J 0
(-3250 3675);
DISPLAY 0.872340 (-3250 3675);
PAINT GREEN (-3250 3675);
DISPLAY INVISIBLE (-3250 3675);
FORCEPROP 1 LAST HDL_TAP TRUE
J 0
(-2925 3500);
DISPLAY 0.872340 (-2925 3500);
DISPLAY INVISIBLE (-2925 3500);
FORCEPROP 1 LAST PATH I205
J 0
(-3252 3625);
DISPLAY 0.872340 (-3252 3625);
PAINT GREEN (-3252 3625);
DISPLAY INVISIBLE (-3252 3625);
FORCEADD TAP..1
(-3250 3575);
FORCEPROP 3 LASTPIN (-3300 3575) SIG_NAME M_I_CPU0_SB_DQ<11>
J 0
(-3290 3585);
DISPLAY 0.659574 (-3290 3585);
PAINT MONO (-3290 3585);
DISPLAY INVISIBLE (-3290 3585);
FORCEPROP 1 LASTPIN (-3300 3575) BN 11
J 0
(-3312 3583);
DISPLAY 0.489362 (-3312 3583);
PAINT GREEN (-3312 3583);
FORCEPROP 2 LAST CDS_LIB mstr_standard
J 0
(-3250 3575);
DISPLAY 0.723404 (-3250 3575);
PAINT MONO (-3250 3575);
DISPLAY INVISIBLE (-3250 3575);
FORCEPROP 1 LAST BODY_TYPE PLUMBING
J 0
(-3250 3625);
DISPLAY 0.872340 (-3250 3625);
PAINT GREEN (-3250 3625);
DISPLAY INVISIBLE (-3250 3625);
FORCEPROP 1 LAST HDL_TAP TRUE
J 0
(-2925 3450);
DISPLAY 0.872340 (-2925 3450);
DISPLAY INVISIBLE (-2925 3450);
FORCEPROP 1 LAST PATH I206
J 0
(-3252 3575);
DISPLAY 0.872340 (-3252 3575);
PAINT GREEN (-3252 3575);
DISPLAY INVISIBLE (-3252 3575);
FORCEADD TAP..1
(-3250 3525);
FORCEPROP 3 LASTPIN (-3300 3525) SIG_NAME M_I_CPU0_SB_DQ<12>
J 0
(-3290 3535);
DISPLAY 0.659574 (-3290 3535);
PAINT MONO (-3290 3535);
DISPLAY INVISIBLE (-3290 3535);
FORCEPROP 1 LASTPIN (-3300 3525) BN 12
J 0
(-3312 3533);
DISPLAY 0.489362 (-3312 3533);
PAINT GREEN (-3312 3533);
FORCEPROP 2 LAST CDS_LIB mstr_standard
J 0
(-3250 3525);
DISPLAY 0.723404 (-3250 3525);
PAINT MONO (-3250 3525);
DISPLAY INVISIBLE (-3250 3525);
FORCEPROP 1 LAST BODY_TYPE PLUMBING
J 0
(-3250 3575);
DISPLAY 0.872340 (-3250 3575);
PAINT GREEN (-3250 3575);
DISPLAY INVISIBLE (-3250 3575);
FORCEPROP 1 LAST HDL_TAP TRUE
J 0
(-2925 3400);
DISPLAY 0.872340 (-2925 3400);
DISPLAY INVISIBLE (-2925 3400);
FORCEPROP 1 LAST PATH I207
J 0
(-3252 3525);
DISPLAY 0.872340 (-3252 3525);
PAINT GREEN (-3252 3525);
DISPLAY INVISIBLE (-3252 3525);
FORCEADD TAP..1
(-3250 3475);
FORCEPROP 3 LASTPIN (-3300 3475) SIG_NAME M_I_CPU0_SB_DQ<13>
J 0
(-3290 3485);
DISPLAY 0.659574 (-3290 3485);
PAINT MONO (-3290 3485);
DISPLAY INVISIBLE (-3290 3485);
FORCEPROP 1 LASTPIN (-3300 3475) BN 13
J 0
(-3312 3483);
DISPLAY 0.489362 (-3312 3483);
PAINT GREEN (-3312 3483);
FORCEPROP 2 LAST CDS_LIB mstr_standard
J 0
(-3250 3475);
DISPLAY 0.723404 (-3250 3475);
PAINT MONO (-3250 3475);
DISPLAY INVISIBLE (-3250 3475);
FORCEPROP 1 LAST BODY_TYPE PLUMBING
J 0
(-3250 3525);
DISPLAY 0.872340 (-3250 3525);
PAINT GREEN (-3250 3525);
DISPLAY INVISIBLE (-3250 3525);
FORCEPROP 1 LAST HDL_TAP TRUE
J 0
(-2925 3350);
DISPLAY 0.872340 (-2925 3350);
DISPLAY INVISIBLE (-2925 3350);
FORCEPROP 1 LAST PATH I208
J 0
(-3252 3475);
DISPLAY 0.872340 (-3252 3475);
PAINT GREEN (-3252 3475);
DISPLAY INVISIBLE (-3252 3475);
FORCEADD TAP..1
(-3250 3375);
FORCEPROP 3 LASTPIN (-3300 3375) SIG_NAME M_I_CPU0_SB_DQ<15>
J 0
(-3290 3385);
DISPLAY 0.659574 (-3290 3385);
PAINT MONO (-3290 3385);
DISPLAY INVISIBLE (-3290 3385);
FORCEPROP 1 LASTPIN (-3300 3375) BN 15
J 0
(-3312 3383);
DISPLAY 0.489362 (-3312 3383);
PAINT GREEN (-3312 3383);
FORCEPROP 2 LAST CDS_LIB mstr_standard
J 0
(-3250 3375);
DISPLAY 0.723404 (-3250 3375);
PAINT MONO (-3250 3375);
DISPLAY INVISIBLE (-3250 3375);
FORCEPROP 1 LAST BODY_TYPE PLUMBING
J 0
(-3250 3425);
DISPLAY 0.872340 (-3250 3425);
PAINT GREEN (-3250 3425);
DISPLAY INVISIBLE (-3250 3425);
FORCEPROP 1 LAST HDL_TAP TRUE
J 0
(-2925 3250);
DISPLAY 0.872340 (-2925 3250);
DISPLAY INVISIBLE (-2925 3250);
FORCEPROP 1 LAST PATH I209
J 0
(-3252 3375);
DISPLAY 0.872340 (-3252 3375);
PAINT GREEN (-3252 3375);
DISPLAY INVISIBLE (-3252 3375);
FORCEADD TAP..1
(-3250 3425);
FORCEPROP 3 LASTPIN (-3300 3425) SIG_NAME M_I_CPU0_SB_DQ<14>
J 0
(-3290 3435);
DISPLAY 0.659574 (-3290 3435);
PAINT MONO (-3290 3435);
DISPLAY INVISIBLE (-3290 3435);
FORCEPROP 1 LASTPIN (-3300 3425) BN 14
J 0
(-3312 3433);
DISPLAY 0.489362 (-3312 3433);
PAINT GREEN (-3312 3433);
FORCEPROP 2 LAST CDS_LIB mstr_standard
J 0
(-3250 3425);
DISPLAY 0.723404 (-3250 3425);
PAINT MONO (-3250 3425);
DISPLAY INVISIBLE (-3250 3425);
FORCEPROP 1 LAST BODY_TYPE PLUMBING
J 0
(-3250 3475);
DISPLAY 0.872340 (-3250 3475);
PAINT GREEN (-3250 3475);
DISPLAY INVISIBLE (-3250 3475);
FORCEPROP 1 LAST HDL_TAP TRUE
J 0
(-2925 3300);
DISPLAY 0.872340 (-2925 3300);
DISPLAY INVISIBLE (-2925 3300);
FORCEPROP 1 LAST PATH I210
J 0
(-3252 3425);
DISPLAY 0.872340 (-3252 3425);
PAINT GREEN (-3252 3425);
DISPLAY INVISIBLE (-3252 3425);
FORCEADD TAP..1
(-3250 3275);
FORCEPROP 3 LASTPIN (-3300 3275) SIG_NAME M_I_CPU0_SB_DQ<16>
J 0
(-3290 3285);
DISPLAY 0.659574 (-3290 3285);
PAINT MONO (-3290 3285);
DISPLAY INVISIBLE (-3290 3285);
FORCEPROP 1 LASTPIN (-3300 3275) BN 16
J 0
(-3312 3283);
DISPLAY 0.489362 (-3312 3283);
PAINT GREEN (-3312 3283);
FORCEPROP 2 LAST CDS_LIB mstr_standard
J 0
(-3250 3275);
DISPLAY 0.723404 (-3250 3275);
PAINT MONO (-3250 3275);
DISPLAY INVISIBLE (-3250 3275);
FORCEPROP 1 LAST BODY_TYPE PLUMBING
J 0
(-3250 3325);
DISPLAY 0.872340 (-3250 3325);
PAINT GREEN (-3250 3325);
DISPLAY INVISIBLE (-3250 3325);
FORCEPROP 1 LAST HDL_TAP TRUE
J 0
(-2925 3150);
DISPLAY 0.872340 (-2925 3150);
DISPLAY INVISIBLE (-2925 3150);
FORCEPROP 1 LAST PATH I211
J 0
(-3252 3275);
DISPLAY 0.872340 (-3252 3275);
PAINT GREEN (-3252 3275);
DISPLAY INVISIBLE (-3252 3275);
FORCEADD TAP..1
(-3250 3225);
FORCEPROP 3 LASTPIN (-3300 3225) SIG_NAME M_I_CPU0_SB_DQ<17>
J 0
(-3290 3235);
DISPLAY 0.659574 (-3290 3235);
PAINT MONO (-3290 3235);
DISPLAY INVISIBLE (-3290 3235);
FORCEPROP 1 LASTPIN (-3300 3225) BN 17
J 0
(-3312 3233);
DISPLAY 0.489362 (-3312 3233);
PAINT GREEN (-3312 3233);
FORCEPROP 2 LAST CDS_LIB mstr_standard
J 0
(-3250 3225);
DISPLAY 0.723404 (-3250 3225);
PAINT MONO (-3250 3225);
DISPLAY INVISIBLE (-3250 3225);
FORCEPROP 1 LAST BODY_TYPE PLUMBING
J 0
(-3250 3275);
DISPLAY 0.872340 (-3250 3275);
PAINT GREEN (-3250 3275);
DISPLAY INVISIBLE (-3250 3275);
FORCEPROP 1 LAST HDL_TAP TRUE
J 0
(-2925 3100);
DISPLAY 0.872340 (-2925 3100);
DISPLAY INVISIBLE (-2925 3100);
FORCEPROP 1 LAST PATH I212
J 0
(-3252 3225);
DISPLAY 0.872340 (-3252 3225);
PAINT GREEN (-3252 3225);
DISPLAY INVISIBLE (-3252 3225);
FORCEADD TAP..1
(-3250 3175);
FORCEPROP 3 LASTPIN (-3300 3175) SIG_NAME M_I_CPU0_SB_DQ<18>
J 0
(-3290 3185);
DISPLAY 0.659574 (-3290 3185);
PAINT MONO (-3290 3185);
DISPLAY INVISIBLE (-3290 3185);
FORCEPROP 1 LASTPIN (-3300 3175) BN 18
J 0
(-3312 3183);
DISPLAY 0.489362 (-3312 3183);
PAINT GREEN (-3312 3183);
FORCEPROP 2 LAST CDS_LIB mstr_standard
J 0
(-3250 3175);
DISPLAY 0.723404 (-3250 3175);
PAINT MONO (-3250 3175);
DISPLAY INVISIBLE (-3250 3175);
FORCEPROP 1 LAST BODY_TYPE PLUMBING
J 0
(-3250 3225);
DISPLAY 0.872340 (-3250 3225);
PAINT GREEN (-3250 3225);
DISPLAY INVISIBLE (-3250 3225);
FORCEPROP 1 LAST HDL_TAP TRUE
J 0
(-2925 3050);
DISPLAY 0.872340 (-2925 3050);
DISPLAY INVISIBLE (-2925 3050);
FORCEPROP 1 LAST PATH I213
J 0
(-3252 3175);
DISPLAY 0.872340 (-3252 3175);
PAINT GREEN (-3252 3175);
DISPLAY INVISIBLE (-3252 3175);
FORCEADD TAP..1
(-3250 3125);
FORCEPROP 3 LASTPIN (-3300 3125) SIG_NAME M_I_CPU0_SB_DQ<19>
J 0
(-3290 3135);
DISPLAY 0.659574 (-3290 3135);
PAINT MONO (-3290 3135);
DISPLAY INVISIBLE (-3290 3135);
FORCEPROP 1 LASTPIN (-3300 3125) BN 19
J 0
(-3312 3133);
DISPLAY 0.489362 (-3312 3133);
PAINT GREEN (-3312 3133);
FORCEPROP 2 LAST CDS_LIB mstr_standard
J 0
(-3250 3125);
DISPLAY 0.723404 (-3250 3125);
PAINT MONO (-3250 3125);
DISPLAY INVISIBLE (-3250 3125);
FORCEPROP 1 LAST BODY_TYPE PLUMBING
J 0
(-3250 3175);
DISPLAY 0.872340 (-3250 3175);
PAINT GREEN (-3250 3175);
DISPLAY INVISIBLE (-3250 3175);
FORCEPROP 1 LAST HDL_TAP TRUE
J 0
(-2925 3000);
DISPLAY 0.872340 (-2925 3000);
DISPLAY INVISIBLE (-2925 3000);
FORCEPROP 1 LAST PATH I214
J 0
(-3252 3125);
DISPLAY 0.872340 (-3252 3125);
PAINT GREEN (-3252 3125);
DISPLAY INVISIBLE (-3252 3125);
FORCEADD TAP..1
(-3250 3075);
FORCEPROP 3 LASTPIN (-3300 3075) SIG_NAME M_I_CPU0_SB_DQ<20>
J 0
(-3290 3085);
DISPLAY 0.659574 (-3290 3085);
PAINT MONO (-3290 3085);
DISPLAY INVISIBLE (-3290 3085);
FORCEPROP 1 LASTPIN (-3300 3075) BN 20
J 0
(-3312 3083);
DISPLAY 0.489362 (-3312 3083);
PAINT GREEN (-3312 3083);
FORCEPROP 2 LAST CDS_LIB mstr_standard
J 0
(-3250 3075);
DISPLAY 0.723404 (-3250 3075);
PAINT MONO (-3250 3075);
DISPLAY INVISIBLE (-3250 3075);
FORCEPROP 1 LAST BODY_TYPE PLUMBING
J 0
(-3250 3125);
DISPLAY 0.872340 (-3250 3125);
PAINT GREEN (-3250 3125);
DISPLAY INVISIBLE (-3250 3125);
FORCEPROP 1 LAST HDL_TAP TRUE
J 0
(-2925 2950);
DISPLAY 0.872340 (-2925 2950);
DISPLAY INVISIBLE (-2925 2950);
FORCEPROP 1 LAST PATH I215
J 0
(-3252 3075);
DISPLAY 0.872340 (-3252 3075);
PAINT GREEN (-3252 3075);
DISPLAY INVISIBLE (-3252 3075);
FORCEADD TAP..1
(-3250 2975);
FORCEPROP 3 LASTPIN (-3300 2975) SIG_NAME M_I_CPU0_SB_DQ<22>
J 0
(-3290 2985);
DISPLAY 0.659574 (-3290 2985);
PAINT MONO (-3290 2985);
DISPLAY INVISIBLE (-3290 2985);
FORCEPROP 1 LASTPIN (-3300 2975) BN 22
J 0
(-3312 2983);
DISPLAY 0.489362 (-3312 2983);
PAINT GREEN (-3312 2983);
FORCEPROP 2 LAST CDS_LIB mstr_standard
J 0
(-3250 2975);
DISPLAY 0.723404 (-3250 2975);
PAINT MONO (-3250 2975);
DISPLAY INVISIBLE (-3250 2975);
FORCEPROP 1 LAST BODY_TYPE PLUMBING
J 0
(-3250 3025);
DISPLAY 0.872340 (-3250 3025);
PAINT GREEN (-3250 3025);
DISPLAY INVISIBLE (-3250 3025);
FORCEPROP 1 LAST HDL_TAP TRUE
J 0
(-2925 2850);
DISPLAY 0.872340 (-2925 2850);
DISPLAY INVISIBLE (-2925 2850);
FORCEPROP 1 LAST PATH I216
J 0
(-3252 2975);
DISPLAY 0.872340 (-3252 2975);
PAINT GREEN (-3252 2975);
DISPLAY INVISIBLE (-3252 2975);
FORCEADD TAP..1
(-3250 3025);
FORCEPROP 3 LASTPIN (-3300 3025) SIG_NAME M_I_CPU0_SB_DQ<21>
J 0
(-3290 3035);
DISPLAY 0.659574 (-3290 3035);
PAINT MONO (-3290 3035);
DISPLAY INVISIBLE (-3290 3035);
FORCEPROP 1 LASTPIN (-3300 3025) BN 21
J 0
(-3312 3033);
DISPLAY 0.489362 (-3312 3033);
PAINT GREEN (-3312 3033);
FORCEPROP 2 LAST CDS_LIB mstr_standard
J 0
(-3250 3025);
DISPLAY 0.723404 (-3250 3025);
PAINT MONO (-3250 3025);
DISPLAY INVISIBLE (-3250 3025);
FORCEPROP 1 LAST BODY_TYPE PLUMBING
J 0
(-3250 3075);
DISPLAY 0.872340 (-3250 3075);
PAINT GREEN (-3250 3075);
DISPLAY INVISIBLE (-3250 3075);
FORCEPROP 1 LAST HDL_TAP TRUE
J 0
(-2925 2900);
DISPLAY 0.872340 (-2925 2900);
DISPLAY INVISIBLE (-2925 2900);
FORCEPROP 1 LAST PATH I217
J 0
(-3252 3025);
DISPLAY 0.872340 (-3252 3025);
PAINT GREEN (-3252 3025);
DISPLAY INVISIBLE (-3252 3025);
FORCEADD TAP..1
(-3250 2925);
FORCEPROP 3 LASTPIN (-3300 2925) SIG_NAME M_I_CPU0_SB_DQ<23>
J 0
(-3290 2935);
DISPLAY 0.659574 (-3290 2935);
PAINT MONO (-3290 2935);
DISPLAY INVISIBLE (-3290 2935);
FORCEPROP 1 LASTPIN (-3300 2925) BN 23
J 0
(-3312 2933);
DISPLAY 0.489362 (-3312 2933);
PAINT GREEN (-3312 2933);
FORCEPROP 2 LAST CDS_LIB mstr_standard
J 0
(-3250 2925);
DISPLAY 0.723404 (-3250 2925);
PAINT MONO (-3250 2925);
DISPLAY INVISIBLE (-3250 2925);
FORCEPROP 1 LAST BODY_TYPE PLUMBING
J 0
(-3250 2975);
DISPLAY 0.872340 (-3250 2975);
PAINT GREEN (-3250 2975);
DISPLAY INVISIBLE (-3250 2975);
FORCEPROP 1 LAST HDL_TAP TRUE
J 0
(-2925 2800);
DISPLAY 0.872340 (-2925 2800);
DISPLAY INVISIBLE (-2925 2800);
FORCEPROP 1 LAST PATH I218
J 0
(-3252 2925);
DISPLAY 0.872340 (-3252 2925);
PAINT GREEN (-3252 2925);
DISPLAY INVISIBLE (-3252 2925);
FORCEADD TAP..1
(-3250 2825);
FORCEPROP 3 LASTPIN (-3300 2825) SIG_NAME M_I_CPU0_SB_DQ<24>
J 0
(-3290 2835);
DISPLAY 0.659574 (-3290 2835);
PAINT MONO (-3290 2835);
DISPLAY INVISIBLE (-3290 2835);
FORCEPROP 1 LASTPIN (-3300 2825) BN 24
J 0
(-3312 2833);
DISPLAY 0.489362 (-3312 2833);
PAINT GREEN (-3312 2833);
FORCEPROP 2 LAST CDS_LIB mstr_standard
J 0
(-3250 2825);
DISPLAY 0.723404 (-3250 2825);
PAINT MONO (-3250 2825);
DISPLAY INVISIBLE (-3250 2825);
FORCEPROP 1 LAST BODY_TYPE PLUMBING
J 0
(-3250 2875);
DISPLAY 0.872340 (-3250 2875);
PAINT GREEN (-3250 2875);
DISPLAY INVISIBLE (-3250 2875);
FORCEPROP 1 LAST HDL_TAP TRUE
J 0
(-2925 2700);
DISPLAY 0.872340 (-2925 2700);
DISPLAY INVISIBLE (-2925 2700);
FORCEPROP 1 LAST PATH I219
J 0
(-3252 2825);
DISPLAY 0.872340 (-3252 2825);
PAINT GREEN (-3252 2825);
DISPLAY INVISIBLE (-3252 2825);
FORCEADD TAP..1
(-3250 2775);
FORCEPROP 3 LASTPIN (-3300 2775) SIG_NAME M_I_CPU0_SB_DQ<25>
J 0
(-3290 2785);
DISPLAY 0.659574 (-3290 2785);
PAINT MONO (-3290 2785);
DISPLAY INVISIBLE (-3290 2785);
FORCEPROP 1 LASTPIN (-3300 2775) BN 25
J 0
(-3312 2783);
DISPLAY 0.489362 (-3312 2783);
PAINT GREEN (-3312 2783);
FORCEPROP 2 LAST CDS_LIB mstr_standard
J 0
(-3250 2775);
DISPLAY 0.723404 (-3250 2775);
PAINT MONO (-3250 2775);
DISPLAY INVISIBLE (-3250 2775);
FORCEPROP 1 LAST BODY_TYPE PLUMBING
J 0
(-3250 2825);
DISPLAY 0.872340 (-3250 2825);
PAINT GREEN (-3250 2825);
DISPLAY INVISIBLE (-3250 2825);
FORCEPROP 1 LAST HDL_TAP TRUE
J 0
(-2925 2650);
DISPLAY 0.872340 (-2925 2650);
DISPLAY INVISIBLE (-2925 2650);
FORCEPROP 1 LAST PATH I220
J 0
(-3252 2775);
DISPLAY 0.872340 (-3252 2775);
PAINT GREEN (-3252 2775);
DISPLAY INVISIBLE (-3252 2775);
FORCEADD TAP..1
(-3250 2725);
FORCEPROP 3 LASTPIN (-3300 2725) SIG_NAME M_I_CPU0_SB_DQ<26>
J 0
(-3290 2735);
DISPLAY 0.659574 (-3290 2735);
PAINT MONO (-3290 2735);
DISPLAY INVISIBLE (-3290 2735);
FORCEPROP 1 LASTPIN (-3300 2725) BN 26
J 0
(-3312 2733);
DISPLAY 0.489362 (-3312 2733);
PAINT GREEN (-3312 2733);
FORCEPROP 2 LAST CDS_LIB mstr_standard
J 0
(-3250 2725);
DISPLAY 0.723404 (-3250 2725);
PAINT MONO (-3250 2725);
DISPLAY INVISIBLE (-3250 2725);
FORCEPROP 1 LAST BODY_TYPE PLUMBING
J 0
(-3250 2775);
DISPLAY 0.872340 (-3250 2775);
PAINT GREEN (-3250 2775);
DISPLAY INVISIBLE (-3250 2775);
FORCEPROP 1 LAST HDL_TAP TRUE
J 0
(-2925 2600);
DISPLAY 0.872340 (-2925 2600);
DISPLAY INVISIBLE (-2925 2600);
FORCEPROP 1 LAST PATH I221
J 0
(-3252 2725);
DISPLAY 0.872340 (-3252 2725);
PAINT GREEN (-3252 2725);
DISPLAY INVISIBLE (-3252 2725);
FORCEADD TAP..1
(-3250 2575);
FORCEPROP 3 LASTPIN (-3300 2575) SIG_NAME M_I_CPU0_SB_DQ<29>
J 0
(-3290 2585);
DISPLAY 0.659574 (-3290 2585);
PAINT MONO (-3290 2585);
DISPLAY INVISIBLE (-3290 2585);
FORCEPROP 1 LASTPIN (-3300 2575) BN 29
J 0
(-3312 2583);
DISPLAY 0.489362 (-3312 2583);
PAINT GREEN (-3312 2583);
FORCEPROP 2 LAST CDS_LIB mstr_standard
J 0
(-3250 2575);
DISPLAY 0.723404 (-3250 2575);
PAINT MONO (-3250 2575);
DISPLAY INVISIBLE (-3250 2575);
FORCEPROP 1 LAST BODY_TYPE PLUMBING
J 0
(-3250 2625);
DISPLAY 0.872340 (-3250 2625);
PAINT GREEN (-3250 2625);
DISPLAY INVISIBLE (-3250 2625);
FORCEPROP 1 LAST HDL_TAP TRUE
J 0
(-2925 2450);
DISPLAY 0.872340 (-2925 2450);
DISPLAY INVISIBLE (-2925 2450);
FORCEPROP 1 LAST PATH I222
J 0
(-3252 2575);
DISPLAY 0.872340 (-3252 2575);
PAINT GREEN (-3252 2575);
DISPLAY INVISIBLE (-3252 2575);
FORCEADD TAP..1
(-3250 2625);
FORCEPROP 3 LASTPIN (-3300 2625) SIG_NAME M_I_CPU0_SB_DQ<28>
J 0
(-3290 2635);
DISPLAY 0.659574 (-3290 2635);
PAINT MONO (-3290 2635);
DISPLAY INVISIBLE (-3290 2635);
FORCEPROP 1 LASTPIN (-3300 2625) BN 28
J 0
(-3312 2633);
DISPLAY 0.489362 (-3312 2633);
PAINT GREEN (-3312 2633);
FORCEPROP 2 LAST CDS_LIB mstr_standard
J 0
(-3250 2625);
DISPLAY 0.723404 (-3250 2625);
PAINT MONO (-3250 2625);
DISPLAY INVISIBLE (-3250 2625);
FORCEPROP 1 LAST BODY_TYPE PLUMBING
J 0
(-3250 2675);
DISPLAY 0.872340 (-3250 2675);
PAINT GREEN (-3250 2675);
DISPLAY INVISIBLE (-3250 2675);
FORCEPROP 1 LAST HDL_TAP TRUE
J 0
(-2925 2500);
DISPLAY 0.872340 (-2925 2500);
DISPLAY INVISIBLE (-2925 2500);
FORCEPROP 1 LAST PATH I223
J 0
(-3252 2625);
DISPLAY 0.872340 (-3252 2625);
PAINT GREEN (-3252 2625);
DISPLAY INVISIBLE (-3252 2625);
FORCEADD TAP..1
(-3250 2675);
FORCEPROP 3 LASTPIN (-3300 2675) SIG_NAME M_I_CPU0_SB_DQ<27>
J 0
(-3290 2685);
DISPLAY 0.659574 (-3290 2685);
PAINT MONO (-3290 2685);
DISPLAY INVISIBLE (-3290 2685);
FORCEPROP 1 LASTPIN (-3300 2675) BN 27
J 0
(-3312 2683);
DISPLAY 0.489362 (-3312 2683);
PAINT GREEN (-3312 2683);
FORCEPROP 2 LAST CDS_LIB mstr_standard
J 0
(-3250 2675);
DISPLAY 0.723404 (-3250 2675);
PAINT MONO (-3250 2675);
DISPLAY INVISIBLE (-3250 2675);
FORCEPROP 1 LAST BODY_TYPE PLUMBING
J 0
(-3250 2725);
DISPLAY 0.872340 (-3250 2725);
PAINT GREEN (-3250 2725);
DISPLAY INVISIBLE (-3250 2725);
FORCEPROP 1 LAST HDL_TAP TRUE
J 0
(-2925 2550);
DISPLAY 0.872340 (-2925 2550);
DISPLAY INVISIBLE (-2925 2550);
FORCEPROP 1 LAST PATH I224
J 0
(-3252 2675);
DISPLAY 0.872340 (-3252 2675);
PAINT GREEN (-3252 2675);
DISPLAY INVISIBLE (-3252 2675);
FORCEADD TAP..1
(-3250 2525);
FORCEPROP 3 LASTPIN (-3300 2525) SIG_NAME M_I_CPU0_SB_DQ<30>
J 0
(-3290 2535);
DISPLAY 0.659574 (-3290 2535);
PAINT MONO (-3290 2535);
DISPLAY INVISIBLE (-3290 2535);
FORCEPROP 1 LASTPIN (-3300 2525) BN 30
J 0
(-3312 2533);
DISPLAY 0.489362 (-3312 2533);
PAINT GREEN (-3312 2533);
FORCEPROP 2 LAST CDS_LIB mstr_standard
J 0
(-3250 2525);
DISPLAY 0.723404 (-3250 2525);
PAINT MONO (-3250 2525);
DISPLAY INVISIBLE (-3250 2525);
FORCEPROP 1 LAST BODY_TYPE PLUMBING
J 0
(-3250 2575);
DISPLAY 0.872340 (-3250 2575);
PAINT GREEN (-3250 2575);
DISPLAY INVISIBLE (-3250 2575);
FORCEPROP 1 LAST HDL_TAP TRUE
J 0
(-2925 2400);
DISPLAY 0.872340 (-2925 2400);
DISPLAY INVISIBLE (-2925 2400);
FORCEPROP 1 LAST PATH I225
J 0
(-3252 2525);
DISPLAY 0.872340 (-3252 2525);
PAINT GREEN (-3252 2525);
DISPLAY INVISIBLE (-3252 2525);
FORCEADD TAP..1
(-3250 2475);
FORCEPROP 3 LASTPIN (-3300 2475) SIG_NAME M_I_CPU0_SB_DQ<31>
J 0
(-3290 2485);
DISPLAY 0.659574 (-3290 2485);
PAINT MONO (-3290 2485);
DISPLAY INVISIBLE (-3290 2485);
FORCEPROP 1 LASTPIN (-3300 2475) BN 31
J 0
(-3312 2483);
DISPLAY 0.489362 (-3312 2483);
PAINT GREEN (-3312 2483);
FORCEPROP 2 LAST CDS_LIB mstr_standard
J 0
(-3250 2475);
DISPLAY 0.723404 (-3250 2475);
PAINT MONO (-3250 2475);
DISPLAY INVISIBLE (-3250 2475);
FORCEPROP 1 LAST BODY_TYPE PLUMBING
J 0
(-3250 2525);
DISPLAY 0.872340 (-3250 2525);
PAINT GREEN (-3250 2525);
DISPLAY INVISIBLE (-3250 2525);
FORCEPROP 1 LAST HDL_TAP TRUE
J 0
(-2925 2350);
DISPLAY 0.872340 (-2925 2350);
DISPLAY INVISIBLE (-2925 2350);
FORCEPROP 1 LAST PATH I226
J 0
(-3252 2475);
DISPLAY 0.872340 (-3252 2475);
PAINT GREEN (-3252 2475);
DISPLAY INVISIBLE (-3252 2475);
FORCEADD TAP..1
(-3250 2325);
FORCEPROP 3 LASTPIN (-3300 2325) SIG_NAME M_I_CPU0_SA_CB<1>
J 0
(-3290 2335);
DISPLAY 0.659574 (-3290 2335);
PAINT MONO (-3290 2335);
DISPLAY INVISIBLE (-3290 2335);
FORCEPROP 1 LASTPIN (-3300 2325) BN 1
J 0
(-3312 2333);
DISPLAY 0.489362 (-3312 2333);
PAINT GREEN (-3312 2333);
FORCEPROP 2 LAST CDS_LIB mstr_standard
J 2
(-3250 2325);
DISPLAY 0.723404 (-3250 2325);
PAINT MONO (-3250 2325);
DISPLAY INVISIBLE (-3250 2325);
FORCEPROP 1 LAST BODY_TYPE PLUMBING
J 0
(-3250 2375);
DISPLAY 0.872340 (-3250 2375);
PAINT GREEN (-3250 2375);
DISPLAY INVISIBLE (-3250 2375);
FORCEPROP 1 LAST HDL_TAP TRUE
J 0
(-2925 2200);
DISPLAY 0.872340 (-2925 2200);
DISPLAY INVISIBLE (-2925 2200);
FORCEPROP 1 LAST PATH I227
J 0
(-3252 2325);
DISPLAY 0.872340 (-3252 2325);
PAINT GREEN (-3252 2325);
DISPLAY INVISIBLE (-3252 2325);
FORCEADD TAP..1
(-3250 2375);
FORCEPROP 3 LASTPIN (-3300 2375) SIG_NAME M_I_CPU0_SA_CB<0>
J 0
(-3290 2385);
DISPLAY 0.659574 (-3290 2385);
PAINT MONO (-3290 2385);
DISPLAY INVISIBLE (-3290 2385);
FORCEPROP 1 LASTPIN (-3300 2375) BN 0
J 0
(-3312 2383);
DISPLAY 0.489362 (-3312 2383);
PAINT GREEN (-3312 2383);
FORCEPROP 2 LAST CDS_LIB mstr_standard
J 2
(-3250 2375);
DISPLAY 0.723404 (-3250 2375);
PAINT MONO (-3250 2375);
DISPLAY INVISIBLE (-3250 2375);
FORCEPROP 1 LAST BODY_TYPE PLUMBING
J 0
(-3250 2425);
DISPLAY 0.872340 (-3250 2425);
PAINT GREEN (-3250 2425);
DISPLAY INVISIBLE (-3250 2425);
FORCEPROP 1 LAST HDL_TAP TRUE
J 0
(-2925 2250);
DISPLAY 0.872340 (-2925 2250);
DISPLAY INVISIBLE (-2925 2250);
FORCEPROP 1 LAST PATH I228
J 0
(-3252 2375);
DISPLAY 0.872340 (-3252 2375);
PAINT GREEN (-3252 2375);
DISPLAY INVISIBLE (-3252 2375);
FORCEADD TAP..1
(-3250 2225);
FORCEPROP 3 LASTPIN (-3300 2225) SIG_NAME M_I_CPU0_SA_CB<3>
J 0
(-3290 2235);
DISPLAY 0.659574 (-3290 2235);
PAINT MONO (-3290 2235);
DISPLAY INVISIBLE (-3290 2235);
FORCEPROP 1 LASTPIN (-3300 2225) BN 3
J 0
(-3312 2233);
DISPLAY 0.489362 (-3312 2233);
PAINT GREEN (-3312 2233);
FORCEPROP 2 LAST CDS_LIB mstr_standard
J 2
(-3250 2225);
DISPLAY 0.723404 (-3250 2225);
PAINT MONO (-3250 2225);
DISPLAY INVISIBLE (-3250 2225);
FORCEPROP 1 LAST BODY_TYPE PLUMBING
J 0
(-3250 2275);
DISPLAY 0.872340 (-3250 2275);
PAINT GREEN (-3250 2275);
DISPLAY INVISIBLE (-3250 2275);
FORCEPROP 1 LAST HDL_TAP TRUE
J 0
(-2925 2100);
DISPLAY 0.872340 (-2925 2100);
DISPLAY INVISIBLE (-2925 2100);
FORCEPROP 1 LAST PATH I229
J 0
(-3252 2225);
DISPLAY 0.872340 (-3252 2225);
PAINT GREEN (-3252 2225);
DISPLAY INVISIBLE (-3252 2225);
FORCEADD TAP..1
(-3250 2275);
FORCEPROP 3 LASTPIN (-3300 2275) SIG_NAME M_I_CPU0_SA_CB<2>
J 0
(-3290 2285);
DISPLAY 0.659574 (-3290 2285);
PAINT MONO (-3290 2285);
DISPLAY INVISIBLE (-3290 2285);
FORCEPROP 1 LASTPIN (-3300 2275) BN 2
J 0
(-3312 2283);
DISPLAY 0.489362 (-3312 2283);
PAINT GREEN (-3312 2283);
FORCEPROP 2 LAST CDS_LIB mstr_standard
J 2
(-3250 2275);
DISPLAY 0.723404 (-3250 2275);
PAINT MONO (-3250 2275);
DISPLAY INVISIBLE (-3250 2275);
FORCEPROP 1 LAST BODY_TYPE PLUMBING
J 0
(-3250 2325);
DISPLAY 0.872340 (-3250 2325);
PAINT GREEN (-3250 2325);
DISPLAY INVISIBLE (-3250 2325);
FORCEPROP 1 LAST HDL_TAP TRUE
J 0
(-2925 2150);
DISPLAY 0.872340 (-2925 2150);
DISPLAY INVISIBLE (-2925 2150);
FORCEPROP 1 LAST PATH I230
J 0
(-3252 2275);
DISPLAY 0.872340 (-3252 2275);
PAINT GREEN (-3252 2275);
DISPLAY INVISIBLE (-3252 2275);
FORCEADD TAP..1
(-3250 2075);
FORCEPROP 3 LASTPIN (-3300 2075) SIG_NAME M_I_CPU0_SA_CB<6>
J 0
(-3290 2085);
DISPLAY 0.659574 (-3290 2085);
PAINT MONO (-3290 2085);
DISPLAY INVISIBLE (-3290 2085);
FORCEPROP 1 LASTPIN (-3300 2075) BN 6
J 0
(-3312 2083);
DISPLAY 0.489362 (-3312 2083);
PAINT GREEN (-3312 2083);
FORCEPROP 2 LAST CDS_LIB mstr_standard
J 2
(-3250 2075);
DISPLAY 0.723404 (-3250 2075);
PAINT MONO (-3250 2075);
DISPLAY INVISIBLE (-3250 2075);
FORCEPROP 1 LAST BODY_TYPE PLUMBING
J 0
(-3250 2125);
DISPLAY 0.872340 (-3250 2125);
PAINT GREEN (-3250 2125);
DISPLAY INVISIBLE (-3250 2125);
FORCEPROP 1 LAST HDL_TAP TRUE
J 0
(-2925 1950);
DISPLAY 0.872340 (-2925 1950);
DISPLAY INVISIBLE (-2925 1950);
FORCEPROP 1 LAST PATH I231
J 0
(-3252 2075);
DISPLAY 0.872340 (-3252 2075);
PAINT GREEN (-3252 2075);
DISPLAY INVISIBLE (-3252 2075);
FORCEADD TAP..1
(-3250 2125);
FORCEPROP 3 LASTPIN (-3300 2125) SIG_NAME M_I_CPU0_SA_CB<5>
J 0
(-3290 2135);
DISPLAY 0.659574 (-3290 2135);
PAINT MONO (-3290 2135);
DISPLAY INVISIBLE (-3290 2135);
FORCEPROP 1 LASTPIN (-3300 2125) BN 5
J 0
(-3312 2133);
DISPLAY 0.489362 (-3312 2133);
PAINT GREEN (-3312 2133);
FORCEPROP 2 LAST CDS_LIB mstr_standard
J 2
(-3250 2125);
DISPLAY 0.723404 (-3250 2125);
PAINT MONO (-3250 2125);
DISPLAY INVISIBLE (-3250 2125);
FORCEPROP 1 LAST BODY_TYPE PLUMBING
J 0
(-3250 2175);
DISPLAY 0.872340 (-3250 2175);
PAINT GREEN (-3250 2175);
DISPLAY INVISIBLE (-3250 2175);
FORCEPROP 1 LAST HDL_TAP TRUE
J 0
(-2925 2000);
DISPLAY 0.872340 (-2925 2000);
DISPLAY INVISIBLE (-2925 2000);
FORCEPROP 1 LAST PATH I232
J 0
(-3252 2125);
DISPLAY 0.872340 (-3252 2125);
PAINT GREEN (-3252 2125);
DISPLAY INVISIBLE (-3252 2125);
FORCEADD TAP..1
(-3250 2175);
FORCEPROP 3 LASTPIN (-3300 2175) SIG_NAME M_I_CPU0_SA_CB<4>
J 0
(-3290 2185);
DISPLAY 0.659574 (-3290 2185);
PAINT MONO (-3290 2185);
DISPLAY INVISIBLE (-3290 2185);
FORCEPROP 1 LASTPIN (-3300 2175) BN 4
J 0
(-3312 2183);
DISPLAY 0.489362 (-3312 2183);
PAINT GREEN (-3312 2183);
FORCEPROP 2 LAST CDS_LIB mstr_standard
J 2
(-3250 2175);
DISPLAY 0.723404 (-3250 2175);
PAINT MONO (-3250 2175);
DISPLAY INVISIBLE (-3250 2175);
FORCEPROP 1 LAST BODY_TYPE PLUMBING
J 0
(-3250 2225);
DISPLAY 0.872340 (-3250 2225);
PAINT GREEN (-3250 2225);
DISPLAY INVISIBLE (-3250 2225);
FORCEPROP 1 LAST HDL_TAP TRUE
J 0
(-2925 2050);
DISPLAY 0.872340 (-2925 2050);
DISPLAY INVISIBLE (-2925 2050);
FORCEPROP 1 LAST PATH I233
J 0
(-3252 2175);
DISPLAY 0.872340 (-3252 2175);
PAINT GREEN (-3252 2175);
DISPLAY INVISIBLE (-3252 2175);
FORCEADD OFFPAGE..6
R 2
(-2650 1975);
FORCEPROP 2 LAST $XR0 94 
J 0
(-2436 1975);
DISPLAY 0.638298 (-2436 1975);
PAINT MONO (-2436 1975);
FORCEPROP 2 LAST CDS_LIB mstr_standard
J 2
(-2650 1975);
DISPLAY 0.723404 (-2650 1975);
PAINT MONO (-2650 1975);
DISPLAY INVISIBLE (-2650 1975);
FORCEPROP 1 LAST OFFPAGE TRUE
J 2
(-2975 1850);
DISPLAY 0.872340 (-2975 1850);
PAINT GREEN (-2975 1850);
DISPLAY INVISIBLE (-2975 1850);
FORCEPROP 1 LAST COMMENT_BODY TRUE
J 2
(-2750 1900);
DISPLAY 0.872340 (-2750 1900);
PAINT GREEN (-2750 1900);
DISPLAY INVISIBLE (-2750 1900);
FORCEPROP 2 LAST PATH I234
J 0
(-2425 2025);
DISPLAY 1.021277 (-2425 2025);
DISPLAY INVISIBLE (-2425 2025);
FORCEADD TAP..1
(-3250 1925);
FORCEPROP 3 LASTPIN (-3300 1925) SIG_NAME M_I_CPU0_SB_CB<0>
J 0
(-3290 1935);
DISPLAY 0.659574 (-3290 1935);
PAINT MONO (-3290 1935);
DISPLAY INVISIBLE (-3290 1935);
FORCEPROP 1 LASTPIN (-3300 1925) BN 0
J 0
(-3312 1933);
DISPLAY 0.489362 (-3312 1933);
PAINT GREEN (-3312 1933);
FORCEPROP 2 LAST CDS_LIB mstr_standard
J 2
(-3250 1925);
DISPLAY 0.723404 (-3250 1925);
PAINT MONO (-3250 1925);
DISPLAY INVISIBLE (-3250 1925);
FORCEPROP 1 LAST BODY_TYPE PLUMBING
J 0
(-3250 1975);
DISPLAY 0.872340 (-3250 1975);
PAINT GREEN (-3250 1975);
DISPLAY INVISIBLE (-3250 1975);
FORCEPROP 1 LAST HDL_TAP TRUE
J 0
(-2925 1800);
DISPLAY 0.872340 (-2925 1800);
DISPLAY INVISIBLE (-2925 1800);
FORCEPROP 1 LAST PATH I235
J 0
(-3252 1925);
DISPLAY 0.872340 (-3252 1925);
PAINT GREEN (-3252 1925);
DISPLAY INVISIBLE (-3252 1925);
FORCEADD TAP..1
(-3250 2025);
FORCEPROP 3 LASTPIN (-3300 2025) SIG_NAME M_I_CPU0_SA_CB<7>
J 0
(-3290 2035);
DISPLAY 0.659574 (-3290 2035);
PAINT MONO (-3290 2035);
DISPLAY INVISIBLE (-3290 2035);
FORCEPROP 1 LASTPIN (-3300 2025) BN 7
J 0
(-3312 2033);
DISPLAY 0.489362 (-3312 2033);
PAINT GREEN (-3312 2033);
FORCEPROP 2 LAST CDS_LIB mstr_standard
J 2
(-3250 2025);
DISPLAY 0.723404 (-3250 2025);
PAINT MONO (-3250 2025);
DISPLAY INVISIBLE (-3250 2025);
FORCEPROP 1 LAST BODY_TYPE PLUMBING
J 0
(-3250 2075);
DISPLAY 0.872340 (-3250 2075);
PAINT GREEN (-3250 2075);
DISPLAY INVISIBLE (-3250 2075);
FORCEPROP 1 LAST HDL_TAP TRUE
J 0
(-2925 1900);
DISPLAY 0.872340 (-2925 1900);
DISPLAY INVISIBLE (-2925 1900);
FORCEPROP 1 LAST PATH I236
J 0
(-3252 2025);
DISPLAY 0.872340 (-3252 2025);
PAINT GREEN (-3252 2025);
DISPLAY INVISIBLE (-3252 2025);
FORCEADD TAP..1
(-3250 1825);
FORCEPROP 3 LASTPIN (-3300 1825) SIG_NAME M_I_CPU0_SB_CB<2>
J 0
(-3290 1835);
DISPLAY 0.659574 (-3290 1835);
PAINT MONO (-3290 1835);
DISPLAY INVISIBLE (-3290 1835);
FORCEPROP 1 LASTPIN (-3300 1825) BN 2
J 0
(-3312 1833);
DISPLAY 0.489362 (-3312 1833);
PAINT GREEN (-3312 1833);
FORCEPROP 2 LAST CDS_LIB mstr_standard
J 2
(-3250 1825);
DISPLAY 0.723404 (-3250 1825);
PAINT MONO (-3250 1825);
DISPLAY INVISIBLE (-3250 1825);
FORCEPROP 1 LAST BODY_TYPE PLUMBING
J 0
(-3250 1875);
DISPLAY 0.872340 (-3250 1875);
PAINT GREEN (-3250 1875);
DISPLAY INVISIBLE (-3250 1875);
FORCEPROP 1 LAST HDL_TAP TRUE
J 0
(-2925 1700);
DISPLAY 0.872340 (-2925 1700);
DISPLAY INVISIBLE (-2925 1700);
FORCEPROP 1 LAST PATH I237
J 0
(-3252 1825);
DISPLAY 0.872340 (-3252 1825);
PAINT GREEN (-3252 1825);
DISPLAY INVISIBLE (-3252 1825);
FORCEADD TAP..1
(-3250 1875);
FORCEPROP 3 LASTPIN (-3300 1875) SIG_NAME M_I_CPU0_SB_CB<1>
J 0
(-3290 1885);
DISPLAY 0.659574 (-3290 1885);
PAINT MONO (-3290 1885);
DISPLAY INVISIBLE (-3290 1885);
FORCEPROP 1 LASTPIN (-3300 1875) BN 1
J 0
(-3312 1883);
DISPLAY 0.489362 (-3312 1883);
PAINT GREEN (-3312 1883);
FORCEPROP 2 LAST CDS_LIB mstr_standard
J 2
(-3250 1875);
DISPLAY 0.723404 (-3250 1875);
PAINT MONO (-3250 1875);
DISPLAY INVISIBLE (-3250 1875);
FORCEPROP 1 LAST BODY_TYPE PLUMBING
J 0
(-3250 1925);
DISPLAY 0.872340 (-3250 1925);
PAINT GREEN (-3250 1925);
DISPLAY INVISIBLE (-3250 1925);
FORCEPROP 1 LAST HDL_TAP TRUE
J 0
(-2925 1750);
DISPLAY 0.872340 (-2925 1750);
DISPLAY INVISIBLE (-2925 1750);
FORCEPROP 1 LAST PATH I238
J 0
(-3252 1875);
DISPLAY 0.872340 (-3252 1875);
PAINT GREEN (-3252 1875);
DISPLAY INVISIBLE (-3252 1875);
FORCEADD TAP..1
(-3250 1775);
FORCEPROP 3 LASTPIN (-3300 1775) SIG_NAME M_I_CPU0_SB_CB<3>
J 0
(-3290 1785);
DISPLAY 0.659574 (-3290 1785);
PAINT MONO (-3290 1785);
DISPLAY INVISIBLE (-3290 1785);
FORCEPROP 1 LASTPIN (-3300 1775) BN 3
J 0
(-3312 1783);
DISPLAY 0.489362 (-3312 1783);
PAINT GREEN (-3312 1783);
FORCEPROP 2 LAST CDS_LIB mstr_standard
J 2
(-3250 1775);
DISPLAY 0.723404 (-3250 1775);
PAINT MONO (-3250 1775);
DISPLAY INVISIBLE (-3250 1775);
FORCEPROP 1 LAST BODY_TYPE PLUMBING
J 0
(-3250 1825);
DISPLAY 0.872340 (-3250 1825);
PAINT GREEN (-3250 1825);
DISPLAY INVISIBLE (-3250 1825);
FORCEPROP 1 LAST HDL_TAP TRUE
J 0
(-2925 1650);
DISPLAY 0.872340 (-2925 1650);
DISPLAY INVISIBLE (-2925 1650);
FORCEPROP 1 LAST PATH I239
J 0
(-3252 1775);
DISPLAY 0.872340 (-3252 1775);
PAINT GREEN (-3252 1775);
DISPLAY INVISIBLE (-3252 1775);
FORCEADD TAP..1
(-3250 1725);
FORCEPROP 3 LASTPIN (-3300 1725) SIG_NAME M_I_CPU0_SB_CB<4>
J 0
(-3290 1735);
DISPLAY 0.659574 (-3290 1735);
PAINT MONO (-3290 1735);
DISPLAY INVISIBLE (-3290 1735);
FORCEPROP 1 LASTPIN (-3300 1725) BN 4
J 0
(-3312 1733);
DISPLAY 0.489362 (-3312 1733);
PAINT GREEN (-3312 1733);
FORCEPROP 2 LAST CDS_LIB mstr_standard
J 2
(-3250 1725);
DISPLAY 0.723404 (-3250 1725);
PAINT MONO (-3250 1725);
DISPLAY INVISIBLE (-3250 1725);
FORCEPROP 1 LAST BODY_TYPE PLUMBING
J 0
(-3250 1775);
DISPLAY 0.872340 (-3250 1775);
PAINT GREEN (-3250 1775);
DISPLAY INVISIBLE (-3250 1775);
FORCEPROP 1 LAST HDL_TAP TRUE
J 0
(-2925 1600);
DISPLAY 0.872340 (-2925 1600);
DISPLAY INVISIBLE (-2925 1600);
FORCEPROP 1 LAST PATH I240
J 0
(-3252 1725);
DISPLAY 0.872340 (-3252 1725);
PAINT GREEN (-3252 1725);
DISPLAY INVISIBLE (-3252 1725);
FORCEADD TAP..1
(-3250 1675);
FORCEPROP 3 LASTPIN (-3300 1675) SIG_NAME M_I_CPU0_SB_CB<5>
J 0
(-3290 1685);
DISPLAY 0.659574 (-3290 1685);
PAINT MONO (-3290 1685);
DISPLAY INVISIBLE (-3290 1685);
FORCEPROP 1 LASTPIN (-3300 1675) BN 5
J 0
(-3312 1683);
DISPLAY 0.489362 (-3312 1683);
PAINT GREEN (-3312 1683);
FORCEPROP 2 LAST CDS_LIB mstr_standard
J 2
(-3250 1675);
DISPLAY 0.723404 (-3250 1675);
PAINT MONO (-3250 1675);
DISPLAY INVISIBLE (-3250 1675);
FORCEPROP 1 LAST BODY_TYPE PLUMBING
J 0
(-3250 1725);
DISPLAY 0.872340 (-3250 1725);
PAINT GREEN (-3250 1725);
DISPLAY INVISIBLE (-3250 1725);
FORCEPROP 1 LAST HDL_TAP TRUE
J 0
(-2925 1550);
DISPLAY 0.872340 (-2925 1550);
DISPLAY INVISIBLE (-2925 1550);
FORCEPROP 1 LAST PATH I241
J 0
(-3252 1675);
DISPLAY 0.872340 (-3252 1675);
PAINT GREEN (-3252 1675);
DISPLAY INVISIBLE (-3252 1675);
FORCEADD TAP..1
(-3250 1575);
FORCEPROP 3 LASTPIN (-3300 1575) SIG_NAME M_I_CPU0_SB_CB<7>
J 0
(-3290 1585);
DISPLAY 0.659574 (-3290 1585);
PAINT MONO (-3290 1585);
DISPLAY INVISIBLE (-3290 1585);
FORCEPROP 1 LASTPIN (-3300 1575) BN 7
J 0
(-3312 1583);
DISPLAY 0.489362 (-3312 1583);
PAINT GREEN (-3312 1583);
FORCEPROP 2 LAST CDS_LIB mstr_standard
J 2
(-3250 1575);
DISPLAY 0.723404 (-3250 1575);
PAINT MONO (-3250 1575);
DISPLAY INVISIBLE (-3250 1575);
FORCEPROP 1 LAST BODY_TYPE PLUMBING
J 0
(-3250 1625);
DISPLAY 0.872340 (-3250 1625);
PAINT GREEN (-3250 1625);
DISPLAY INVISIBLE (-3250 1625);
FORCEPROP 1 LAST HDL_TAP TRUE
J 0
(-2925 1450);
DISPLAY 0.872340 (-2925 1450);
DISPLAY INVISIBLE (-2925 1450);
FORCEPROP 1 LAST PATH I242
J 0
(-3252 1575);
DISPLAY 0.872340 (-3252 1575);
PAINT GREEN (-3252 1575);
DISPLAY INVISIBLE (-3252 1575);
FORCEADD TAP..1
(-3250 1625);
FORCEPROP 3 LASTPIN (-3300 1625) SIG_NAME M_I_CPU0_SB_CB<6>
J 0
(-3290 1635);
DISPLAY 0.659574 (-3290 1635);
PAINT MONO (-3290 1635);
DISPLAY INVISIBLE (-3290 1635);
FORCEPROP 1 LASTPIN (-3300 1625) BN 6
J 0
(-3312 1633);
DISPLAY 0.489362 (-3312 1633);
PAINT GREEN (-3312 1633);
FORCEPROP 2 LAST CDS_LIB mstr_standard
J 2
(-3250 1625);
DISPLAY 0.723404 (-3250 1625);
PAINT MONO (-3250 1625);
DISPLAY INVISIBLE (-3250 1625);
FORCEPROP 1 LAST BODY_TYPE PLUMBING
J 0
(-3250 1675);
DISPLAY 0.872340 (-3250 1675);
PAINT GREEN (-3250 1675);
DISPLAY INVISIBLE (-3250 1675);
FORCEPROP 1 LAST HDL_TAP TRUE
J 0
(-2925 1500);
DISPLAY 0.872340 (-2925 1500);
DISPLAY INVISIBLE (-2925 1500);
FORCEPROP 1 LAST PATH I243
J 0
(-3252 1625);
DISPLAY 0.872340 (-3252 1625);
PAINT GREEN (-3252 1625);
DISPLAY INVISIBLE (-3252 1625);
FORCEADD TAP..1
R 2
(-5675 5975);
FORCEPROP 3 LASTPIN (-5625 5975) SIG_NAME M_I_CPU0_SA_DQS_DP<0>
J 0
(-5615 5985);
DISPLAY 0.659574 (-5615 5985);
PAINT MONO (-5615 5985);
DISPLAY INVISIBLE (-5615 5985);
FORCEPROP 1 LASTPIN (-5625 5975) BN 0
J 2
(-5613 5983);
DISPLAY 0.489362 (-5613 5983);
PAINT GREEN (-5613 5983);
FORCEPROP 2 LAST CDS_LIB mstr_standard
J 2
(-5675 5975);
DISPLAY 0.723404 (-5675 5975);
PAINT MONO (-5675 5975);
DISPLAY INVISIBLE (-5675 5975);
FORCEPROP 1 LAST BODY_TYPE PLUMBING
J 2
(-5675 6025);
DISPLAY 0.872340 (-5675 6025);
PAINT GREEN (-5675 6025);
DISPLAY INVISIBLE (-5675 6025);
FORCEPROP 1 LAST HDL_TAP TRUE
J 2
(-6000 5850);
DISPLAY 0.872340 (-6000 5850);
DISPLAY INVISIBLE (-6000 5850);
FORCEPROP 1 LAST PATH I244
J 2
(-5673 5975);
DISPLAY 0.872340 (-5673 5975);
PAINT GREEN (-5673 5975);
DISPLAY INVISIBLE (-5673 5975);
FORCEADD TAP..1
R 2
(-5675 5875);
FORCEPROP 3 LASTPIN (-5625 5875) SIG_NAME M_I_CPU0_SA_DQS_DP<1>
J 0
(-5615 5885);
DISPLAY 0.659574 (-5615 5885);
PAINT MONO (-5615 5885);
DISPLAY INVISIBLE (-5615 5885);
FORCEPROP 1 LASTPIN (-5625 5875) BN 1
J 2
(-5613 5883);
DISPLAY 0.489362 (-5613 5883);
PAINT GREEN (-5613 5883);
FORCEPROP 2 LAST CDS_LIB mstr_standard
J 2
(-5675 5875);
DISPLAY 0.723404 (-5675 5875);
PAINT MONO (-5675 5875);
DISPLAY INVISIBLE (-5675 5875);
FORCEPROP 1 LAST BODY_TYPE PLUMBING
J 2
(-5675 5925);
DISPLAY 0.872340 (-5675 5925);
PAINT GREEN (-5675 5925);
DISPLAY INVISIBLE (-5675 5925);
FORCEPROP 1 LAST HDL_TAP TRUE
J 2
(-6000 5750);
DISPLAY 0.872340 (-6000 5750);
DISPLAY INVISIBLE (-6000 5750);
FORCEPROP 1 LAST PATH I245
J 2
(-5673 5875);
DISPLAY 0.872340 (-5673 5875);
PAINT GREEN (-5673 5875);
DISPLAY INVISIBLE (-5673 5875);
FORCEADD TAP..1
R 2
(-5675 5775);
FORCEPROP 3 LASTPIN (-5625 5775) SIG_NAME M_I_CPU0_SA_DQS_DP<2>
J 0
(-5615 5785);
DISPLAY 0.659574 (-5615 5785);
PAINT MONO (-5615 5785);
DISPLAY INVISIBLE (-5615 5785);
FORCEPROP 1 LASTPIN (-5625 5775) BN 2
J 2
(-5613 5783);
DISPLAY 0.489362 (-5613 5783);
PAINT GREEN (-5613 5783);
FORCEPROP 2 LAST CDS_LIB mstr_standard
J 2
(-5675 5775);
DISPLAY 0.723404 (-5675 5775);
PAINT MONO (-5675 5775);
DISPLAY INVISIBLE (-5675 5775);
FORCEPROP 1 LAST BODY_TYPE PLUMBING
J 2
(-5675 5825);
DISPLAY 0.872340 (-5675 5825);
PAINT GREEN (-5675 5825);
DISPLAY INVISIBLE (-5675 5825);
FORCEPROP 1 LAST HDL_TAP TRUE
J 2
(-6000 5650);
DISPLAY 0.872340 (-6000 5650);
DISPLAY INVISIBLE (-6000 5650);
FORCEPROP 1 LAST PATH I246
J 2
(-5673 5775);
DISPLAY 0.872340 (-5673 5775);
PAINT GREEN (-5673 5775);
DISPLAY INVISIBLE (-5673 5775);
FORCEADD TAP..1
R 2
(-5675 5675);
FORCEPROP 3 LASTPIN (-5625 5675) SIG_NAME M_I_CPU0_SA_DQS_DP<3>
J 0
(-5615 5685);
DISPLAY 0.659574 (-5615 5685);
PAINT MONO (-5615 5685);
DISPLAY INVISIBLE (-5615 5685);
FORCEPROP 1 LASTPIN (-5625 5675) BN 3
J 2
(-5613 5683);
DISPLAY 0.489362 (-5613 5683);
PAINT GREEN (-5613 5683);
FORCEPROP 2 LAST CDS_LIB mstr_standard
J 2
(-5675 5675);
DISPLAY 0.723404 (-5675 5675);
PAINT MONO (-5675 5675);
DISPLAY INVISIBLE (-5675 5675);
FORCEPROP 1 LAST BODY_TYPE PLUMBING
J 2
(-5675 5725);
DISPLAY 0.872340 (-5675 5725);
PAINT GREEN (-5675 5725);
DISPLAY INVISIBLE (-5675 5725);
FORCEPROP 1 LAST HDL_TAP TRUE
J 2
(-6000 5550);
DISPLAY 0.872340 (-6000 5550);
DISPLAY INVISIBLE (-6000 5550);
FORCEPROP 1 LAST PATH I247
J 2
(-5673 5675);
DISPLAY 0.872340 (-5673 5675);
PAINT GREEN (-5673 5675);
DISPLAY INVISIBLE (-5673 5675);
FORCEADD TAP..1
R 2
(-5675 5575);
FORCEPROP 3 LASTPIN (-5625 5575) SIG_NAME M_I_CPU0_SA_DQS_DP<4>
J 0
(-5615 5585);
DISPLAY 0.659574 (-5615 5585);
PAINT MONO (-5615 5585);
DISPLAY INVISIBLE (-5615 5585);
FORCEPROP 1 LASTPIN (-5625 5575) BN 4
J 2
(-5613 5583);
DISPLAY 0.489362 (-5613 5583);
PAINT GREEN (-5613 5583);
FORCEPROP 2 LAST CDS_LIB mstr_standard
J 2
(-5675 5575);
DISPLAY 0.723404 (-5675 5575);
PAINT MONO (-5675 5575);
DISPLAY INVISIBLE (-5675 5575);
FORCEPROP 1 LAST BODY_TYPE PLUMBING
J 2
(-5675 5625);
DISPLAY 0.872340 (-5675 5625);
PAINT GREEN (-5675 5625);
DISPLAY INVISIBLE (-5675 5625);
FORCEPROP 1 LAST HDL_TAP TRUE
J 2
(-6000 5450);
DISPLAY 0.872340 (-6000 5450);
DISPLAY INVISIBLE (-6000 5450);
FORCEPROP 1 LAST PATH I248
J 2
(-5673 5575);
DISPLAY 0.872340 (-5673 5575);
PAINT GREEN (-5673 5575);
DISPLAY INVISIBLE (-5673 5575);
FORCEADD TAP..1
R 2
(-5675 5475);
FORCEPROP 3 LASTPIN (-5625 5475) SIG_NAME M_I_CPU0_SA_DQS_DP<5>
J 0
(-5615 5485);
DISPLAY 0.659574 (-5615 5485);
PAINT MONO (-5615 5485);
DISPLAY INVISIBLE (-5615 5485);
FORCEPROP 1 LASTPIN (-5625 5475) BN 5
J 2
(-5613 5483);
DISPLAY 0.489362 (-5613 5483);
PAINT GREEN (-5613 5483);
FORCEPROP 2 LAST CDS_LIB mstr_standard
J 2
(-5675 5475);
DISPLAY 0.723404 (-5675 5475);
PAINT MONO (-5675 5475);
DISPLAY INVISIBLE (-5675 5475);
FORCEPROP 1 LAST BODY_TYPE PLUMBING
J 2
(-5675 5525);
DISPLAY 0.872340 (-5675 5525);
PAINT GREEN (-5675 5525);
DISPLAY INVISIBLE (-5675 5525);
FORCEPROP 1 LAST HDL_TAP TRUE
J 2
(-6000 5350);
DISPLAY 0.872340 (-6000 5350);
DISPLAY INVISIBLE (-6000 5350);
FORCEPROP 1 LAST PATH I249
J 2
(-5673 5475);
DISPLAY 0.872340 (-5673 5475);
PAINT GREEN (-5673 5475);
DISPLAY INVISIBLE (-5673 5475);
FORCEADD TAP..1
R 2
(-5675 5375);
FORCEPROP 3 LASTPIN (-5625 5375) SIG_NAME M_I_CPU0_SA_DQS_DP<6>
J 0
(-5615 5385);
DISPLAY 0.659574 (-5615 5385);
PAINT MONO (-5615 5385);
DISPLAY INVISIBLE (-5615 5385);
FORCEPROP 1 LASTPIN (-5625 5375) BN 6
J 2
(-5613 5383);
DISPLAY 0.489362 (-5613 5383);
PAINT GREEN (-5613 5383);
FORCEPROP 2 LAST CDS_LIB mstr_standard
J 2
(-5675 5375);
DISPLAY 0.723404 (-5675 5375);
PAINT MONO (-5675 5375);
DISPLAY INVISIBLE (-5675 5375);
FORCEPROP 1 LAST BODY_TYPE PLUMBING
J 2
(-5675 5425);
DISPLAY 0.872340 (-5675 5425);
PAINT GREEN (-5675 5425);
DISPLAY INVISIBLE (-5675 5425);
FORCEPROP 1 LAST HDL_TAP TRUE
J 2
(-6000 5250);
DISPLAY 0.872340 (-6000 5250);
DISPLAY INVISIBLE (-6000 5250);
FORCEPROP 1 LAST PATH I250
J 2
(-5673 5375);
DISPLAY 0.872340 (-5673 5375);
PAINT GREEN (-5673 5375);
DISPLAY INVISIBLE (-5673 5375);
FORCEADD TAP..1
R 2
(-5675 5275);
FORCEPROP 3 LASTPIN (-5625 5275) SIG_NAME M_I_CPU0_SA_DQS_DP<7>
J 0
(-5615 5285);
DISPLAY 0.659574 (-5615 5285);
PAINT MONO (-5615 5285);
DISPLAY INVISIBLE (-5615 5285);
FORCEPROP 1 LASTPIN (-5625 5275) BN 7
J 2
(-5613 5283);
DISPLAY 0.489362 (-5613 5283);
PAINT GREEN (-5613 5283);
FORCEPROP 2 LAST CDS_LIB mstr_standard
J 2
(-5675 5275);
DISPLAY 0.723404 (-5675 5275);
PAINT MONO (-5675 5275);
DISPLAY INVISIBLE (-5675 5275);
FORCEPROP 1 LAST BODY_TYPE PLUMBING
J 2
(-5675 5325);
DISPLAY 0.872340 (-5675 5325);
PAINT GREEN (-5675 5325);
DISPLAY INVISIBLE (-5675 5325);
FORCEPROP 1 LAST HDL_TAP TRUE
J 2
(-6000 5150);
DISPLAY 0.872340 (-6000 5150);
DISPLAY INVISIBLE (-6000 5150);
FORCEPROP 1 LAST PATH I251
J 2
(-5673 5275);
DISPLAY 0.872340 (-5673 5275);
PAINT GREEN (-5673 5275);
DISPLAY INVISIBLE (-5673 5275);
FORCEADD TAP..1
R 2
(-5675 5175);
FORCEPROP 3 LASTPIN (-5625 5175) SIG_NAME M_I_CPU0_SA_DQS_DP<8>
J 0
(-5615 5185);
DISPLAY 0.659574 (-5615 5185);
PAINT MONO (-5615 5185);
DISPLAY INVISIBLE (-5615 5185);
FORCEPROP 1 LASTPIN (-5625 5175) BN 8
J 2
(-5613 5183);
DISPLAY 0.489362 (-5613 5183);
PAINT GREEN (-5613 5183);
FORCEPROP 2 LAST CDS_LIB mstr_standard
J 2
(-5675 5175);
DISPLAY 0.723404 (-5675 5175);
PAINT MONO (-5675 5175);
DISPLAY INVISIBLE (-5675 5175);
FORCEPROP 1 LAST BODY_TYPE PLUMBING
J 2
(-5675 5225);
DISPLAY 0.872340 (-5675 5225);
PAINT GREEN (-5675 5225);
DISPLAY INVISIBLE (-5675 5225);
FORCEPROP 1 LAST HDL_TAP TRUE
J 2
(-6000 5050);
DISPLAY 0.872340 (-6000 5050);
DISPLAY INVISIBLE (-6000 5050);
FORCEPROP 1 LAST PATH I252
J 2
(-5673 5175);
DISPLAY 0.872340 (-5673 5175);
PAINT GREEN (-5673 5175);
DISPLAY INVISIBLE (-5673 5175);
FORCEADD TAP..1
R 2
(-5875 5925);
FORCEPROP 3 LASTPIN (-5825 5925) SIG_NAME M_I_CPU0_SA_DQS_DN<0>
J 0
(-5815 5935);
DISPLAY 0.659574 (-5815 5935);
PAINT MONO (-5815 5935);
DISPLAY INVISIBLE (-5815 5935);
FORCEPROP 1 LASTPIN (-5825 5925) BN 0
J 2
(-5813 5933);
DISPLAY 0.489362 (-5813 5933);
PAINT GREEN (-5813 5933);
FORCEPROP 2 LAST CDS_LIB mstr_standard
J 2
(-5875 5925);
DISPLAY 0.723404 (-5875 5925);
PAINT MONO (-5875 5925);
DISPLAY INVISIBLE (-5875 5925);
FORCEPROP 1 LAST BODY_TYPE PLUMBING
J 2
(-5875 5975);
DISPLAY 0.872340 (-5875 5975);
PAINT GREEN (-5875 5975);
DISPLAY INVISIBLE (-5875 5975);
FORCEPROP 1 LAST HDL_TAP TRUE
J 2
(-6200 5800);
DISPLAY 0.872340 (-6200 5800);
DISPLAY INVISIBLE (-6200 5800);
FORCEPROP 1 LAST PATH I253
J 2
(-5873 5925);
DISPLAY 0.872340 (-5873 5925);
PAINT GREEN (-5873 5925);
DISPLAY INVISIBLE (-5873 5925);
FORCEADD TAP..1
R 2
(-5875 5825);
FORCEPROP 3 LASTPIN (-5825 5825) SIG_NAME M_I_CPU0_SA_DQS_DN<1>
J 0
(-5815 5835);
DISPLAY 0.659574 (-5815 5835);
PAINT MONO (-5815 5835);
DISPLAY INVISIBLE (-5815 5835);
FORCEPROP 1 LASTPIN (-5825 5825) BN 1
J 2
(-5813 5833);
DISPLAY 0.489362 (-5813 5833);
PAINT GREEN (-5813 5833);
FORCEPROP 2 LAST CDS_LIB mstr_standard
J 2
(-5875 5825);
DISPLAY 0.723404 (-5875 5825);
PAINT MONO (-5875 5825);
DISPLAY INVISIBLE (-5875 5825);
FORCEPROP 1 LAST BODY_TYPE PLUMBING
J 2
(-5875 5875);
DISPLAY 0.872340 (-5875 5875);
PAINT GREEN (-5875 5875);
DISPLAY INVISIBLE (-5875 5875);
FORCEPROP 1 LAST HDL_TAP TRUE
J 2
(-6200 5700);
DISPLAY 0.872340 (-6200 5700);
DISPLAY INVISIBLE (-6200 5700);
FORCEPROP 1 LAST PATH I254
J 2
(-5873 5825);
DISPLAY 0.872340 (-5873 5825);
PAINT GREEN (-5873 5825);
DISPLAY INVISIBLE (-5873 5825);
FORCEADD TAP..1
R 2
(-5875 5725);
FORCEPROP 3 LASTPIN (-5825 5725) SIG_NAME M_I_CPU0_SA_DQS_DN<2>
J 0
(-5815 5735);
DISPLAY 0.659574 (-5815 5735);
PAINT MONO (-5815 5735);
DISPLAY INVISIBLE (-5815 5735);
FORCEPROP 1 LASTPIN (-5825 5725) BN 2
J 2
(-5813 5733);
DISPLAY 0.489362 (-5813 5733);
PAINT GREEN (-5813 5733);
FORCEPROP 2 LAST CDS_LIB mstr_standard
J 2
(-5875 5725);
DISPLAY 0.723404 (-5875 5725);
PAINT MONO (-5875 5725);
DISPLAY INVISIBLE (-5875 5725);
FORCEPROP 1 LAST BODY_TYPE PLUMBING
J 2
(-5875 5775);
DISPLAY 0.872340 (-5875 5775);
PAINT GREEN (-5875 5775);
DISPLAY INVISIBLE (-5875 5775);
FORCEPROP 1 LAST HDL_TAP TRUE
J 2
(-6200 5600);
DISPLAY 0.872340 (-6200 5600);
DISPLAY INVISIBLE (-6200 5600);
FORCEPROP 1 LAST PATH I255
J 2
(-5873 5725);
DISPLAY 0.872340 (-5873 5725);
PAINT GREEN (-5873 5725);
DISPLAY INVISIBLE (-5873 5725);
FORCEADD TAP..1
R 2
(-5875 5525);
FORCEPROP 3 LASTPIN (-5825 5525) SIG_NAME M_I_CPU0_SA_DQS_DN<4>
J 0
(-5815 5535);
DISPLAY 0.659574 (-5815 5535);
PAINT MONO (-5815 5535);
DISPLAY INVISIBLE (-5815 5535);
FORCEPROP 1 LASTPIN (-5825 5525) BN 4
J 2
(-5813 5533);
DISPLAY 0.489362 (-5813 5533);
PAINT GREEN (-5813 5533);
FORCEPROP 2 LAST CDS_LIB mstr_standard
J 2
(-5875 5525);
DISPLAY 0.723404 (-5875 5525);
PAINT MONO (-5875 5525);
DISPLAY INVISIBLE (-5875 5525);
FORCEPROP 1 LAST BODY_TYPE PLUMBING
J 2
(-5875 5575);
DISPLAY 0.872340 (-5875 5575);
PAINT GREEN (-5875 5575);
DISPLAY INVISIBLE (-5875 5575);
FORCEPROP 1 LAST HDL_TAP TRUE
J 2
(-6200 5400);
DISPLAY 0.872340 (-6200 5400);
DISPLAY INVISIBLE (-6200 5400);
FORCEPROP 1 LAST PATH I256
J 2
(-5873 5525);
DISPLAY 0.872340 (-5873 5525);
PAINT GREEN (-5873 5525);
DISPLAY INVISIBLE (-5873 5525);
FORCEADD TAP..1
R 2
(-5875 5625);
FORCEPROP 3 LASTPIN (-5825 5625) SIG_NAME M_I_CPU0_SA_DQS_DN<3>
J 0
(-5815 5635);
DISPLAY 0.659574 (-5815 5635);
PAINT MONO (-5815 5635);
DISPLAY INVISIBLE (-5815 5635);
FORCEPROP 1 LASTPIN (-5825 5625) BN 3
J 2
(-5813 5633);
DISPLAY 0.489362 (-5813 5633);
PAINT GREEN (-5813 5633);
FORCEPROP 2 LAST CDS_LIB mstr_standard
J 2
(-5875 5625);
DISPLAY 0.723404 (-5875 5625);
PAINT MONO (-5875 5625);
DISPLAY INVISIBLE (-5875 5625);
FORCEPROP 1 LAST BODY_TYPE PLUMBING
J 2
(-5875 5675);
DISPLAY 0.872340 (-5875 5675);
PAINT GREEN (-5875 5675);
DISPLAY INVISIBLE (-5875 5675);
FORCEPROP 1 LAST HDL_TAP TRUE
J 2
(-6200 5500);
DISPLAY 0.872340 (-6200 5500);
DISPLAY INVISIBLE (-6200 5500);
FORCEPROP 1 LAST PATH I257
J 2
(-5873 5625);
DISPLAY 0.872340 (-5873 5625);
PAINT GREEN (-5873 5625);
DISPLAY INVISIBLE (-5873 5625);
FORCEADD TAP..1
R 2
(-5875 5425);
FORCEPROP 3 LASTPIN (-5825 5425) SIG_NAME M_I_CPU0_SA_DQS_DN<5>
J 0
(-5815 5435);
DISPLAY 0.659574 (-5815 5435);
PAINT MONO (-5815 5435);
DISPLAY INVISIBLE (-5815 5435);
FORCEPROP 1 LASTPIN (-5825 5425) BN 5
J 2
(-5813 5433);
DISPLAY 0.489362 (-5813 5433);
PAINT GREEN (-5813 5433);
FORCEPROP 2 LAST CDS_LIB mstr_standard
J 2
(-5875 5425);
DISPLAY 0.723404 (-5875 5425);
PAINT MONO (-5875 5425);
DISPLAY INVISIBLE (-5875 5425);
FORCEPROP 1 LAST BODY_TYPE PLUMBING
J 2
(-5875 5475);
DISPLAY 0.872340 (-5875 5475);
PAINT GREEN (-5875 5475);
DISPLAY INVISIBLE (-5875 5475);
FORCEPROP 1 LAST HDL_TAP TRUE
J 2
(-6200 5300);
DISPLAY 0.872340 (-6200 5300);
DISPLAY INVISIBLE (-6200 5300);
FORCEPROP 1 LAST PATH I258
J 2
(-5873 5425);
DISPLAY 0.872340 (-5873 5425);
PAINT GREEN (-5873 5425);
DISPLAY INVISIBLE (-5873 5425);
FORCEADD TAP..1
R 2
(-5875 5325);
FORCEPROP 3 LASTPIN (-5825 5325) SIG_NAME M_I_CPU0_SA_DQS_DN<6>
J 0
(-5815 5335);
DISPLAY 0.659574 (-5815 5335);
PAINT MONO (-5815 5335);
DISPLAY INVISIBLE (-5815 5335);
FORCEPROP 1 LASTPIN (-5825 5325) BN 6
J 2
(-5813 5333);
DISPLAY 0.489362 (-5813 5333);
PAINT GREEN (-5813 5333);
FORCEPROP 2 LAST CDS_LIB mstr_standard
J 2
(-5875 5325);
DISPLAY 0.723404 (-5875 5325);
PAINT MONO (-5875 5325);
DISPLAY INVISIBLE (-5875 5325);
FORCEPROP 1 LAST BODY_TYPE PLUMBING
J 2
(-5875 5375);
DISPLAY 0.872340 (-5875 5375);
PAINT GREEN (-5875 5375);
DISPLAY INVISIBLE (-5875 5375);
FORCEPROP 1 LAST HDL_TAP TRUE
J 2
(-6200 5200);
DISPLAY 0.872340 (-6200 5200);
DISPLAY INVISIBLE (-6200 5200);
FORCEPROP 1 LAST PATH I259
J 2
(-5873 5325);
DISPLAY 0.872340 (-5873 5325);
PAINT GREEN (-5873 5325);
DISPLAY INVISIBLE (-5873 5325);
FORCEADD TAP..1
R 2
(-5875 5225);
FORCEPROP 3 LASTPIN (-5825 5225) SIG_NAME M_I_CPU0_SA_DQS_DN<7>
J 0
(-5815 5235);
DISPLAY 0.659574 (-5815 5235);
PAINT MONO (-5815 5235);
DISPLAY INVISIBLE (-5815 5235);
FORCEPROP 1 LASTPIN (-5825 5225) BN 7
J 2
(-5813 5233);
DISPLAY 0.489362 (-5813 5233);
PAINT GREEN (-5813 5233);
FORCEPROP 2 LAST CDS_LIB mstr_standard
J 2
(-5875 5225);
DISPLAY 0.723404 (-5875 5225);
PAINT MONO (-5875 5225);
DISPLAY INVISIBLE (-5875 5225);
FORCEPROP 1 LAST BODY_TYPE PLUMBING
J 2
(-5875 5275);
DISPLAY 0.872340 (-5875 5275);
PAINT GREEN (-5875 5275);
DISPLAY INVISIBLE (-5875 5275);
FORCEPROP 1 LAST HDL_TAP TRUE
J 2
(-6200 5100);
DISPLAY 0.872340 (-6200 5100);
DISPLAY INVISIBLE (-6200 5100);
FORCEPROP 1 LAST PATH I260
J 2
(-5873 5225);
DISPLAY 0.872340 (-5873 5225);
PAINT GREEN (-5873 5225);
DISPLAY INVISIBLE (-5873 5225);
FORCEADD TAP..1
R 2
(-5875 5125);
FORCEPROP 3 LASTPIN (-5825 5125) SIG_NAME M_I_CPU0_SA_DQS_DN<8>
J 0
(-5815 5135);
DISPLAY 0.659574 (-5815 5135);
PAINT MONO (-5815 5135);
DISPLAY INVISIBLE (-5815 5135);
FORCEPROP 1 LASTPIN (-5825 5125) BN 8
J 2
(-5813 5133);
DISPLAY 0.489362 (-5813 5133);
PAINT GREEN (-5813 5133);
FORCEPROP 2 LAST CDS_LIB mstr_standard
J 2
(-5875 5125);
DISPLAY 0.723404 (-5875 5125);
PAINT MONO (-5875 5125);
DISPLAY INVISIBLE (-5875 5125);
FORCEPROP 1 LAST BODY_TYPE PLUMBING
J 2
(-5875 5175);
DISPLAY 0.872340 (-5875 5175);
PAINT GREEN (-5875 5175);
DISPLAY INVISIBLE (-5875 5175);
FORCEPROP 1 LAST HDL_TAP TRUE
J 2
(-6200 5000);
DISPLAY 0.872340 (-6200 5000);
DISPLAY INVISIBLE (-6200 5000);
FORCEPROP 1 LAST PATH I261
J 2
(-5873 5125);
DISPLAY 0.872340 (-5873 5125);
PAINT GREEN (-5873 5125);
DISPLAY INVISIBLE (-5873 5125);
FORCEADD TAP..1
R 2
(-5675 5075);
FORCEPROP 3 LASTPIN (-5625 5075) SIG_NAME M_I_CPU0_SA_DQS_DP<9>
J 0
(-5615 5085);
DISPLAY 0.659574 (-5615 5085);
PAINT MONO (-5615 5085);
DISPLAY INVISIBLE (-5615 5085);
FORCEPROP 1 LASTPIN (-5625 5075) BN 9
J 2
(-5613 5083);
DISPLAY 0.489362 (-5613 5083);
PAINT GREEN (-5613 5083);
FORCEPROP 2 LAST CDS_LIB mstr_standard
J 2
(-5675 5075);
DISPLAY 0.723404 (-5675 5075);
PAINT MONO (-5675 5075);
DISPLAY INVISIBLE (-5675 5075);
FORCEPROP 1 LAST BODY_TYPE PLUMBING
J 2
(-5675 5125);
DISPLAY 0.872340 (-5675 5125);
PAINT GREEN (-5675 5125);
DISPLAY INVISIBLE (-5675 5125);
FORCEPROP 1 LAST HDL_TAP TRUE
J 2
(-6000 4950);
DISPLAY 0.872340 (-6000 4950);
DISPLAY INVISIBLE (-6000 4950);
FORCEPROP 1 LAST PATH I262
J 2
(-5673 5075);
DISPLAY 0.872340 (-5673 5075);
PAINT GREEN (-5673 5075);
DISPLAY INVISIBLE (-5673 5075);
FORCEADD TAP..1
R 2
(-5675 4925);
FORCEPROP 3 LASTPIN (-5625 4925) SIG_NAME M_I_CPU0_SB_DQS_DP<0>
J 0
(-5615 4935);
DISPLAY 0.659574 (-5615 4935);
PAINT MONO (-5615 4935);
DISPLAY INVISIBLE (-5615 4935);
FORCEPROP 1 LASTPIN (-5625 4925) BN 0
J 2
(-5613 4933);
DISPLAY 0.489362 (-5613 4933);
PAINT GREEN (-5613 4933);
FORCEPROP 2 LAST CDS_LIB mstr_standard
J 2
(-5675 4925);
DISPLAY 0.723404 (-5675 4925);
PAINT MONO (-5675 4925);
DISPLAY INVISIBLE (-5675 4925);
FORCEPROP 1 LAST BODY_TYPE PLUMBING
J 2
(-5675 4975);
DISPLAY 0.872340 (-5675 4975);
PAINT GREEN (-5675 4975);
DISPLAY INVISIBLE (-5675 4975);
FORCEPROP 1 LAST HDL_TAP TRUE
J 2
(-6000 4800);
DISPLAY 0.872340 (-6000 4800);
DISPLAY INVISIBLE (-6000 4800);
FORCEPROP 1 LAST PATH I263
J 2
(-5673 4925);
DISPLAY 0.872340 (-5673 4925);
PAINT GREEN (-5673 4925);
DISPLAY INVISIBLE (-5673 4925);
FORCEADD TAP..1
R 2
(-5675 4825);
FORCEPROP 3 LASTPIN (-5625 4825) SIG_NAME M_I_CPU0_SB_DQS_DP<1>
J 0
(-5615 4835);
DISPLAY 0.659574 (-5615 4835);
PAINT MONO (-5615 4835);
DISPLAY INVISIBLE (-5615 4835);
FORCEPROP 1 LASTPIN (-5625 4825) BN 1
J 2
(-5613 4833);
DISPLAY 0.489362 (-5613 4833);
PAINT GREEN (-5613 4833);
FORCEPROP 2 LAST CDS_LIB mstr_standard
J 2
(-5675 4825);
DISPLAY 0.723404 (-5675 4825);
PAINT MONO (-5675 4825);
DISPLAY INVISIBLE (-5675 4825);
FORCEPROP 1 LAST BODY_TYPE PLUMBING
J 2
(-5675 4875);
DISPLAY 0.872340 (-5675 4875);
PAINT GREEN (-5675 4875);
DISPLAY INVISIBLE (-5675 4875);
FORCEPROP 1 LAST HDL_TAP TRUE
J 2
(-6000 4700);
DISPLAY 0.872340 (-6000 4700);
DISPLAY INVISIBLE (-6000 4700);
FORCEPROP 1 LAST PATH I264
J 2
(-5673 4825);
DISPLAY 0.872340 (-5673 4825);
PAINT GREEN (-5673 4825);
DISPLAY INVISIBLE (-5673 4825);
FORCEADD TAP..1
R 2
(-5675 4725);
FORCEPROP 3 LASTPIN (-5625 4725) SIG_NAME M_I_CPU0_SB_DQS_DP<2>
J 0
(-5615 4735);
DISPLAY 0.659574 (-5615 4735);
PAINT MONO (-5615 4735);
DISPLAY INVISIBLE (-5615 4735);
FORCEPROP 1 LASTPIN (-5625 4725) BN 2
J 2
(-5613 4733);
DISPLAY 0.489362 (-5613 4733);
PAINT GREEN (-5613 4733);
FORCEPROP 2 LAST CDS_LIB mstr_standard
J 2
(-5675 4725);
DISPLAY 0.723404 (-5675 4725);
PAINT MONO (-5675 4725);
DISPLAY INVISIBLE (-5675 4725);
FORCEPROP 1 LAST BODY_TYPE PLUMBING
J 2
(-5675 4775);
DISPLAY 0.872340 (-5675 4775);
PAINT GREEN (-5675 4775);
DISPLAY INVISIBLE (-5675 4775);
FORCEPROP 1 LAST HDL_TAP TRUE
J 2
(-6000 4600);
DISPLAY 0.872340 (-6000 4600);
DISPLAY INVISIBLE (-6000 4600);
FORCEPROP 1 LAST PATH I265
J 2
(-5673 4725);
DISPLAY 0.872340 (-5673 4725);
PAINT GREEN (-5673 4725);
DISPLAY INVISIBLE (-5673 4725);
FORCEADD TAP..1
R 2
(-5675 4625);
FORCEPROP 3 LASTPIN (-5625 4625) SIG_NAME M_I_CPU0_SB_DQS_DP<3>
J 0
(-5615 4635);
DISPLAY 0.659574 (-5615 4635);
PAINT MONO (-5615 4635);
DISPLAY INVISIBLE (-5615 4635);
FORCEPROP 1 LASTPIN (-5625 4625) BN 3
J 2
(-5613 4633);
DISPLAY 0.489362 (-5613 4633);
PAINT GREEN (-5613 4633);
FORCEPROP 2 LAST CDS_LIB mstr_standard
J 2
(-5675 4625);
DISPLAY 0.723404 (-5675 4625);
PAINT MONO (-5675 4625);
DISPLAY INVISIBLE (-5675 4625);
FORCEPROP 1 LAST BODY_TYPE PLUMBING
J 2
(-5675 4675);
DISPLAY 0.872340 (-5675 4675);
PAINT GREEN (-5675 4675);
DISPLAY INVISIBLE (-5675 4675);
FORCEPROP 1 LAST HDL_TAP TRUE
J 2
(-6000 4500);
DISPLAY 0.872340 (-6000 4500);
DISPLAY INVISIBLE (-6000 4500);
FORCEPROP 1 LAST PATH I266
J 2
(-5673 4625);
DISPLAY 0.872340 (-5673 4625);
PAINT GREEN (-5673 4625);
DISPLAY INVISIBLE (-5673 4625);
FORCEADD TAP..1
R 2
(-5675 4525);
FORCEPROP 3 LASTPIN (-5625 4525) SIG_NAME M_I_CPU0_SB_DQS_DP<4>
J 0
(-5615 4535);
DISPLAY 0.659574 (-5615 4535);
PAINT MONO (-5615 4535);
DISPLAY INVISIBLE (-5615 4535);
FORCEPROP 1 LASTPIN (-5625 4525) BN 4
J 2
(-5613 4533);
DISPLAY 0.489362 (-5613 4533);
PAINT GREEN (-5613 4533);
FORCEPROP 2 LAST CDS_LIB mstr_standard
J 2
(-5675 4525);
DISPLAY 0.723404 (-5675 4525);
PAINT MONO (-5675 4525);
DISPLAY INVISIBLE (-5675 4525);
FORCEPROP 1 LAST BODY_TYPE PLUMBING
J 2
(-5675 4575);
DISPLAY 0.872340 (-5675 4575);
PAINT GREEN (-5675 4575);
DISPLAY INVISIBLE (-5675 4575);
FORCEPROP 1 LAST HDL_TAP TRUE
J 2
(-6000 4400);
DISPLAY 0.872340 (-6000 4400);
DISPLAY INVISIBLE (-6000 4400);
FORCEPROP 1 LAST PATH I267
J 2
(-5673 4525);
DISPLAY 0.872340 (-5673 4525);
PAINT GREEN (-5673 4525);
DISPLAY INVISIBLE (-5673 4525);
FORCEADD TAP..1
R 2
(-5675 4425);
FORCEPROP 3 LASTPIN (-5625 4425) SIG_NAME M_I_CPU0_SB_DQS_DP<5>
J 0
(-5615 4435);
DISPLAY 0.659574 (-5615 4435);
PAINT MONO (-5615 4435);
DISPLAY INVISIBLE (-5615 4435);
FORCEPROP 1 LASTPIN (-5625 4425) BN 5
J 2
(-5613 4433);
DISPLAY 0.489362 (-5613 4433);
PAINT GREEN (-5613 4433);
FORCEPROP 2 LAST CDS_LIB mstr_standard
J 2
(-5675 4425);
DISPLAY 0.723404 (-5675 4425);
PAINT MONO (-5675 4425);
DISPLAY INVISIBLE (-5675 4425);
FORCEPROP 1 LAST BODY_TYPE PLUMBING
J 2
(-5675 4475);
DISPLAY 0.872340 (-5675 4475);
PAINT GREEN (-5675 4475);
DISPLAY INVISIBLE (-5675 4475);
FORCEPROP 1 LAST HDL_TAP TRUE
J 2
(-6000 4300);
DISPLAY 0.872340 (-6000 4300);
DISPLAY INVISIBLE (-6000 4300);
FORCEPROP 1 LAST PATH I268
J 2
(-5673 4425);
DISPLAY 0.872340 (-5673 4425);
PAINT GREEN (-5673 4425);
DISPLAY INVISIBLE (-5673 4425);
FORCEADD TAP..1
R 2
(-5675 4325);
FORCEPROP 3 LASTPIN (-5625 4325) SIG_NAME M_I_CPU0_SB_DQS_DP<6>
J 0
(-5615 4335);
DISPLAY 0.659574 (-5615 4335);
PAINT MONO (-5615 4335);
DISPLAY INVISIBLE (-5615 4335);
FORCEPROP 1 LASTPIN (-5625 4325) BN 6
J 2
(-5613 4333);
DISPLAY 0.489362 (-5613 4333);
PAINT GREEN (-5613 4333);
FORCEPROP 2 LAST CDS_LIB mstr_standard
J 2
(-5675 4325);
DISPLAY 0.723404 (-5675 4325);
PAINT MONO (-5675 4325);
DISPLAY INVISIBLE (-5675 4325);
FORCEPROP 1 LAST BODY_TYPE PLUMBING
J 2
(-5675 4375);
DISPLAY 0.872340 (-5675 4375);
PAINT GREEN (-5675 4375);
DISPLAY INVISIBLE (-5675 4375);
FORCEPROP 1 LAST HDL_TAP TRUE
J 2
(-6000 4200);
DISPLAY 0.872340 (-6000 4200);
DISPLAY INVISIBLE (-6000 4200);
FORCEPROP 1 LAST PATH I269
J 2
(-5673 4325);
DISPLAY 0.872340 (-5673 4325);
PAINT GREEN (-5673 4325);
DISPLAY INVISIBLE (-5673 4325);
FORCEADD TAP..1
R 2
(-5675 4225);
FORCEPROP 3 LASTPIN (-5625 4225) SIG_NAME M_I_CPU0_SB_DQS_DP<7>
J 0
(-5615 4235);
DISPLAY 0.659574 (-5615 4235);
PAINT MONO (-5615 4235);
DISPLAY INVISIBLE (-5615 4235);
FORCEPROP 1 LASTPIN (-5625 4225) BN 7
J 2
(-5613 4233);
DISPLAY 0.489362 (-5613 4233);
PAINT GREEN (-5613 4233);
FORCEPROP 2 LAST CDS_LIB mstr_standard
J 2
(-5675 4225);
DISPLAY 0.723404 (-5675 4225);
PAINT MONO (-5675 4225);
DISPLAY INVISIBLE (-5675 4225);
FORCEPROP 1 LAST BODY_TYPE PLUMBING
J 2
(-5675 4275);
DISPLAY 0.872340 (-5675 4275);
PAINT GREEN (-5675 4275);
DISPLAY INVISIBLE (-5675 4275);
FORCEPROP 1 LAST HDL_TAP TRUE
J 2
(-6000 4100);
DISPLAY 0.872340 (-6000 4100);
DISPLAY INVISIBLE (-6000 4100);
FORCEPROP 1 LAST PATH I270
J 2
(-5673 4225);
DISPLAY 0.872340 (-5673 4225);
PAINT GREEN (-5673 4225);
DISPLAY INVISIBLE (-5673 4225);
FORCEADD TAP..1
R 2
(-5675 4125);
FORCEPROP 3 LASTPIN (-5625 4125) SIG_NAME M_I_CPU0_SB_DQS_DP<8>
J 0
(-5615 4135);
DISPLAY 0.659574 (-5615 4135);
PAINT MONO (-5615 4135);
DISPLAY INVISIBLE (-5615 4135);
FORCEPROP 1 LASTPIN (-5625 4125) BN 8
J 2
(-5613 4133);
DISPLAY 0.489362 (-5613 4133);
PAINT GREEN (-5613 4133);
FORCEPROP 2 LAST CDS_LIB mstr_standard
J 2
(-5675 4125);
DISPLAY 0.723404 (-5675 4125);
PAINT MONO (-5675 4125);
DISPLAY INVISIBLE (-5675 4125);
FORCEPROP 1 LAST BODY_TYPE PLUMBING
J 2
(-5675 4175);
DISPLAY 0.872340 (-5675 4175);
PAINT GREEN (-5675 4175);
DISPLAY INVISIBLE (-5675 4175);
FORCEPROP 1 LAST HDL_TAP TRUE
J 2
(-6000 4000);
DISPLAY 0.872340 (-6000 4000);
DISPLAY INVISIBLE (-6000 4000);
FORCEPROP 1 LAST PATH I271
J 2
(-5673 4125);
DISPLAY 0.872340 (-5673 4125);
PAINT GREEN (-5673 4125);
DISPLAY INVISIBLE (-5673 4125);
FORCEADD TAP..1
R 2
(-5875 4875);
FORCEPROP 3 LASTPIN (-5825 4875) SIG_NAME M_I_CPU0_SB_DQS_DN<0>
J 0
(-5815 4885);
DISPLAY 0.659574 (-5815 4885);
PAINT MONO (-5815 4885);
DISPLAY INVISIBLE (-5815 4885);
FORCEPROP 1 LASTPIN (-5825 4875) BN 0
J 2
(-5813 4883);
DISPLAY 0.489362 (-5813 4883);
PAINT GREEN (-5813 4883);
FORCEPROP 2 LAST CDS_LIB mstr_standard
J 2
(-5875 4875);
DISPLAY 0.723404 (-5875 4875);
PAINT MONO (-5875 4875);
DISPLAY INVISIBLE (-5875 4875);
FORCEPROP 1 LAST BODY_TYPE PLUMBING
J 2
(-5875 4925);
DISPLAY 0.872340 (-5875 4925);
PAINT GREEN (-5875 4925);
DISPLAY INVISIBLE (-5875 4925);
FORCEPROP 1 LAST HDL_TAP TRUE
J 2
(-6200 4750);
DISPLAY 0.872340 (-6200 4750);
DISPLAY INVISIBLE (-6200 4750);
FORCEPROP 1 LAST PATH I272
J 2
(-5873 4875);
DISPLAY 0.872340 (-5873 4875);
PAINT GREEN (-5873 4875);
DISPLAY INVISIBLE (-5873 4875);
FORCEADD TAP..1
R 2
(-5875 5025);
FORCEPROP 3 LASTPIN (-5825 5025) SIG_NAME M_I_CPU0_SA_DQS_DN<9>
J 0
(-5815 5035);
DISPLAY 0.659574 (-5815 5035);
PAINT MONO (-5815 5035);
DISPLAY INVISIBLE (-5815 5035);
FORCEPROP 1 LASTPIN (-5825 5025) BN 9
J 2
(-5813 5033);
DISPLAY 0.489362 (-5813 5033);
PAINT GREEN (-5813 5033);
FORCEPROP 2 LAST CDS_LIB mstr_standard
J 2
(-5875 5025);
DISPLAY 0.723404 (-5875 5025);
PAINT MONO (-5875 5025);
DISPLAY INVISIBLE (-5875 5025);
FORCEPROP 1 LAST BODY_TYPE PLUMBING
J 2
(-5875 5075);
DISPLAY 0.872340 (-5875 5075);
PAINT GREEN (-5875 5075);
DISPLAY INVISIBLE (-5875 5075);
FORCEPROP 1 LAST HDL_TAP TRUE
J 2
(-6200 4900);
DISPLAY 0.872340 (-6200 4900);
DISPLAY INVISIBLE (-6200 4900);
FORCEPROP 1 LAST PATH I273
J 2
(-5873 5025);
DISPLAY 0.872340 (-5873 5025);
PAINT GREEN (-5873 5025);
DISPLAY INVISIBLE (-5873 5025);
FORCEADD TAP..1
R 2
(-5875 4775);
FORCEPROP 3 LASTPIN (-5825 4775) SIG_NAME M_I_CPU0_SB_DQS_DN<1>
J 0
(-5815 4785);
DISPLAY 0.659574 (-5815 4785);
PAINT MONO (-5815 4785);
DISPLAY INVISIBLE (-5815 4785);
FORCEPROP 1 LASTPIN (-5825 4775) BN 1
J 2
(-5813 4783);
DISPLAY 0.489362 (-5813 4783);
PAINT GREEN (-5813 4783);
FORCEPROP 2 LAST CDS_LIB mstr_standard
J 2
(-5875 4775);
DISPLAY 0.723404 (-5875 4775);
PAINT MONO (-5875 4775);
DISPLAY INVISIBLE (-5875 4775);
FORCEPROP 1 LAST BODY_TYPE PLUMBING
J 2
(-5875 4825);
DISPLAY 0.872340 (-5875 4825);
PAINT GREEN (-5875 4825);
DISPLAY INVISIBLE (-5875 4825);
FORCEPROP 1 LAST HDL_TAP TRUE
J 2
(-6200 4650);
DISPLAY 0.872340 (-6200 4650);
DISPLAY INVISIBLE (-6200 4650);
FORCEPROP 1 LAST PATH I274
J 2
(-5873 4775);
DISPLAY 0.872340 (-5873 4775);
PAINT GREEN (-5873 4775);
DISPLAY INVISIBLE (-5873 4775);
FORCEADD TAP..1
R 2
(-5875 4675);
FORCEPROP 3 LASTPIN (-5825 4675) SIG_NAME M_I_CPU0_SB_DQS_DN<2>
J 0
(-5815 4685);
DISPLAY 0.659574 (-5815 4685);
PAINT MONO (-5815 4685);
DISPLAY INVISIBLE (-5815 4685);
FORCEPROP 1 LASTPIN (-5825 4675) BN 2
J 2
(-5813 4683);
DISPLAY 0.489362 (-5813 4683);
PAINT GREEN (-5813 4683);
FORCEPROP 2 LAST CDS_LIB mstr_standard
J 2
(-5875 4675);
DISPLAY 0.723404 (-5875 4675);
PAINT MONO (-5875 4675);
DISPLAY INVISIBLE (-5875 4675);
FORCEPROP 1 LAST BODY_TYPE PLUMBING
J 2
(-5875 4725);
DISPLAY 0.872340 (-5875 4725);
PAINT GREEN (-5875 4725);
DISPLAY INVISIBLE (-5875 4725);
FORCEPROP 1 LAST HDL_TAP TRUE
J 2
(-6200 4550);
DISPLAY 0.872340 (-6200 4550);
DISPLAY INVISIBLE (-6200 4550);
FORCEPROP 1 LAST PATH I275
J 2
(-5873 4675);
DISPLAY 0.872340 (-5873 4675);
PAINT GREEN (-5873 4675);
DISPLAY INVISIBLE (-5873 4675);
FORCEADD TAP..1
R 2
(-5875 4575);
FORCEPROP 3 LASTPIN (-5825 4575) SIG_NAME M_I_CPU0_SB_DQS_DN<3>
J 0
(-5815 4585);
DISPLAY 0.659574 (-5815 4585);
PAINT MONO (-5815 4585);
DISPLAY INVISIBLE (-5815 4585);
FORCEPROP 1 LASTPIN (-5825 4575) BN 3
J 2
(-5813 4583);
DISPLAY 0.489362 (-5813 4583);
PAINT GREEN (-5813 4583);
FORCEPROP 2 LAST CDS_LIB mstr_standard
J 2
(-5875 4575);
DISPLAY 0.723404 (-5875 4575);
PAINT MONO (-5875 4575);
DISPLAY INVISIBLE (-5875 4575);
FORCEPROP 1 LAST BODY_TYPE PLUMBING
J 2
(-5875 4625);
DISPLAY 0.872340 (-5875 4625);
PAINT GREEN (-5875 4625);
DISPLAY INVISIBLE (-5875 4625);
FORCEPROP 1 LAST HDL_TAP TRUE
J 2
(-6200 4450);
DISPLAY 0.872340 (-6200 4450);
DISPLAY INVISIBLE (-6200 4450);
FORCEPROP 1 LAST PATH I276
J 2
(-5873 4575);
DISPLAY 0.872340 (-5873 4575);
PAINT GREEN (-5873 4575);
DISPLAY INVISIBLE (-5873 4575);
FORCEADD TAP..1
R 2
(-5875 4375);
FORCEPROP 3 LASTPIN (-5825 4375) SIG_NAME M_I_CPU0_SB_DQS_DN<5>
J 0
(-5815 4385);
DISPLAY 0.659574 (-5815 4385);
PAINT MONO (-5815 4385);
DISPLAY INVISIBLE (-5815 4385);
FORCEPROP 1 LASTPIN (-5825 4375) BN 5
J 2
(-5813 4383);
DISPLAY 0.489362 (-5813 4383);
PAINT GREEN (-5813 4383);
FORCEPROP 2 LAST CDS_LIB mstr_standard
J 2
(-5875 4375);
DISPLAY 0.723404 (-5875 4375);
PAINT MONO (-5875 4375);
DISPLAY INVISIBLE (-5875 4375);
FORCEPROP 1 LAST BODY_TYPE PLUMBING
J 2
(-5875 4425);
DISPLAY 0.872340 (-5875 4425);
PAINT GREEN (-5875 4425);
DISPLAY INVISIBLE (-5875 4425);
FORCEPROP 1 LAST HDL_TAP TRUE
J 2
(-6200 4250);
DISPLAY 0.872340 (-6200 4250);
DISPLAY INVISIBLE (-6200 4250);
FORCEPROP 1 LAST PATH I277
J 2
(-5873 4375);
DISPLAY 0.872340 (-5873 4375);
PAINT GREEN (-5873 4375);
DISPLAY INVISIBLE (-5873 4375);
FORCEADD TAP..1
R 2
(-5875 4475);
FORCEPROP 3 LASTPIN (-5825 4475) SIG_NAME M_I_CPU0_SB_DQS_DN<4>
J 0
(-5815 4485);
DISPLAY 0.659574 (-5815 4485);
PAINT MONO (-5815 4485);
DISPLAY INVISIBLE (-5815 4485);
FORCEPROP 1 LASTPIN (-5825 4475) BN 4
J 2
(-5813 4483);
DISPLAY 0.489362 (-5813 4483);
PAINT GREEN (-5813 4483);
FORCEPROP 2 LAST CDS_LIB mstr_standard
J 2
(-5875 4475);
DISPLAY 0.723404 (-5875 4475);
PAINT MONO (-5875 4475);
DISPLAY INVISIBLE (-5875 4475);
FORCEPROP 1 LAST BODY_TYPE PLUMBING
J 2
(-5875 4525);
DISPLAY 0.872340 (-5875 4525);
PAINT GREEN (-5875 4525);
DISPLAY INVISIBLE (-5875 4525);
FORCEPROP 1 LAST HDL_TAP TRUE
J 2
(-6200 4350);
DISPLAY 0.872340 (-6200 4350);
DISPLAY INVISIBLE (-6200 4350);
FORCEPROP 1 LAST PATH I278
J 2
(-5873 4475);
DISPLAY 0.872340 (-5873 4475);
PAINT GREEN (-5873 4475);
DISPLAY INVISIBLE (-5873 4475);
FORCEADD TAP..1
R 2
(-5875 4275);
FORCEPROP 3 LASTPIN (-5825 4275) SIG_NAME M_I_CPU0_SB_DQS_DN<6>
J 0
(-5815 4285);
DISPLAY 0.659574 (-5815 4285);
PAINT MONO (-5815 4285);
DISPLAY INVISIBLE (-5815 4285);
FORCEPROP 1 LASTPIN (-5825 4275) BN 6
J 2
(-5813 4283);
DISPLAY 0.489362 (-5813 4283);
PAINT GREEN (-5813 4283);
FORCEPROP 2 LAST CDS_LIB mstr_standard
J 2
(-5875 4275);
DISPLAY 0.723404 (-5875 4275);
PAINT MONO (-5875 4275);
DISPLAY INVISIBLE (-5875 4275);
FORCEPROP 1 LAST BODY_TYPE PLUMBING
J 2
(-5875 4325);
DISPLAY 0.872340 (-5875 4325);
PAINT GREEN (-5875 4325);
DISPLAY INVISIBLE (-5875 4325);
FORCEPROP 1 LAST HDL_TAP TRUE
J 2
(-6200 4150);
DISPLAY 0.872340 (-6200 4150);
DISPLAY INVISIBLE (-6200 4150);
FORCEPROP 1 LAST PATH I279
J 2
(-5873 4275);
DISPLAY 0.872340 (-5873 4275);
PAINT GREEN (-5873 4275);
DISPLAY INVISIBLE (-5873 4275);
FORCEADD TAP..1
R 2
(-5875 4175);
FORCEPROP 3 LASTPIN (-5825 4175) SIG_NAME M_I_CPU0_SB_DQS_DN<7>
J 0
(-5815 4185);
DISPLAY 0.659574 (-5815 4185);
PAINT MONO (-5815 4185);
DISPLAY INVISIBLE (-5815 4185);
FORCEPROP 1 LASTPIN (-5825 4175) BN 7
J 2
(-5813 4183);
DISPLAY 0.489362 (-5813 4183);
PAINT GREEN (-5813 4183);
FORCEPROP 2 LAST CDS_LIB mstr_standard
J 2
(-5875 4175);
DISPLAY 0.723404 (-5875 4175);
PAINT MONO (-5875 4175);
DISPLAY INVISIBLE (-5875 4175);
FORCEPROP 1 LAST BODY_TYPE PLUMBING
J 2
(-5875 4225);
DISPLAY 0.872340 (-5875 4225);
PAINT GREEN (-5875 4225);
DISPLAY INVISIBLE (-5875 4225);
FORCEPROP 1 LAST HDL_TAP TRUE
J 2
(-6200 4050);
DISPLAY 0.872340 (-6200 4050);
DISPLAY INVISIBLE (-6200 4050);
FORCEPROP 1 LAST PATH I280
J 2
(-5873 4175);
DISPLAY 0.872340 (-5873 4175);
PAINT GREEN (-5873 4175);
DISPLAY INVISIBLE (-5873 4175);
FORCEADD OFFPAGE..3
R 2
(-6575 5950);
FORCEPROP 2 LAST $XR0 94 
J 0
(-6854 5950);
DISPLAY 0.638298 (-6854 5950);
PAINT MONO (-6854 5950);
FORCEPROP 2 LAST CDS_LIB standard
J 0
(-6575 5950);
DISPLAY INVISIBLE (-6575 5950);
FORCEPROP 1 LAST OFFPAGE TRUE
J 2
(-6900 5825);
DISPLAY 0.872340 (-6900 5825);
PAINT GREEN (-6900 5825);
DISPLAY INVISIBLE (-6900 5825);
FORCEPROP 1 LAST COMMENT_BODY TRUE
J 2
(-6525 5850);
DISPLAY 0.872340 (-6525 5850);
PAINT GREEN (-6525 5850);
DISPLAY INVISIBLE (-6525 5850);
FORCEPROP 2 LAST PATH I281
J 0
(-6875 6000);
DISPLAY 1.021277 (-6875 6000);
DISPLAY INVISIBLE (-6875 6000);
FORCEADD OFFPAGE..3
R 2
(-6575 6000);
FORCEPROP 2 LAST $XR0 94 
J 0
(-6854 6000);
DISPLAY 0.638298 (-6854 6000);
PAINT MONO (-6854 6000);
FORCEPROP 2 LAST CDS_LIB standard
J 0
(-6575 6000);
DISPLAY INVISIBLE (-6575 6000);
FORCEPROP 1 LAST OFFPAGE TRUE
J 2
(-6900 5875);
DISPLAY 0.872340 (-6900 5875);
PAINT GREEN (-6900 5875);
DISPLAY INVISIBLE (-6900 5875);
FORCEPROP 1 LAST COMMENT_BODY TRUE
J 2
(-6525 5900);
DISPLAY 0.872340 (-6525 5900);
PAINT GREEN (-6525 5900);
DISPLAY INVISIBLE (-6525 5900);
FORCEPROP 2 LAST PATH I282
J 0
(-6875 6050);
DISPLAY 1.021277 (-6875 6050);
DISPLAY INVISIBLE (-6875 6050);
FORCEADD OFFPAGE..3
R 2
(-6575 4900);
FORCEPROP 2 LAST $XR0 94 
J 0
(-6854 4900);
DISPLAY 0.638298 (-6854 4900);
PAINT MONO (-6854 4900);
FORCEPROP 2 LAST CDS_LIB standard
J 0
(-6575 4900);
DISPLAY INVISIBLE (-6575 4900);
FORCEPROP 1 LAST OFFPAGE TRUE
J 2
(-6900 4775);
DISPLAY 0.872340 (-6900 4775);
PAINT GREEN (-6900 4775);
DISPLAY INVISIBLE (-6900 4775);
FORCEPROP 1 LAST COMMENT_BODY TRUE
J 2
(-6525 4800);
DISPLAY 0.872340 (-6525 4800);
PAINT GREEN (-6525 4800);
DISPLAY INVISIBLE (-6525 4800);
FORCEPROP 2 LAST PATH I283
J 0
(-6875 4950);
DISPLAY 1.021277 (-6875 4950);
DISPLAY INVISIBLE (-6875 4950);
FORCEADD OFFPAGE..3
R 2
(-6575 4950);
FORCEPROP 2 LAST $XR0 94 
J 0
(-6854 4950);
DISPLAY 0.638298 (-6854 4950);
PAINT MONO (-6854 4950);
FORCEPROP 2 LAST CDS_LIB standard
J 0
(-6575 4950);
DISPLAY INVISIBLE (-6575 4950);
FORCEPROP 1 LAST OFFPAGE TRUE
J 2
(-6900 4825);
DISPLAY 0.872340 (-6900 4825);
PAINT GREEN (-6900 4825);
DISPLAY INVISIBLE (-6900 4825);
FORCEPROP 1 LAST COMMENT_BODY TRUE
J 2
(-6525 4850);
DISPLAY 0.872340 (-6525 4850);
PAINT GREEN (-6525 4850);
DISPLAY INVISIBLE (-6525 4850);
FORCEPROP 2 LAST PATH I284
J 0
(-6875 5000);
DISPLAY 1.021277 (-6875 5000);
DISPLAY INVISIBLE (-6875 5000);
FORCEADD TAP..1
R 2
(-5675 4025);
FORCEPROP 3 LASTPIN (-5625 4025) SIG_NAME M_I_CPU0_SB_DQS_DP<9>
J 0
(-5615 4035);
DISPLAY 0.659574 (-5615 4035);
PAINT MONO (-5615 4035);
DISPLAY INVISIBLE (-5615 4035);
FORCEPROP 1 LASTPIN (-5625 4025) BN 9
J 2
(-5613 4033);
DISPLAY 0.489362 (-5613 4033);
PAINT GREEN (-5613 4033);
FORCEPROP 2 LAST CDS_LIB mstr_standard
J 2
(-5675 4025);
DISPLAY 0.723404 (-5675 4025);
PAINT MONO (-5675 4025);
DISPLAY INVISIBLE (-5675 4025);
FORCEPROP 1 LAST BODY_TYPE PLUMBING
J 2
(-5675 4075);
DISPLAY 0.872340 (-5675 4075);
PAINT GREEN (-5675 4075);
DISPLAY INVISIBLE (-5675 4075);
FORCEPROP 1 LAST HDL_TAP TRUE
J 2
(-6000 3900);
DISPLAY 0.872340 (-6000 3900);
DISPLAY INVISIBLE (-6000 3900);
FORCEPROP 1 LAST PATH I285
J 2
(-5673 4025);
DISPLAY 0.872340 (-5673 4025);
PAINT GREEN (-5673 4025);
DISPLAY INVISIBLE (-5673 4025);
FORCEADD TAP..1
R 2
(-5875 4075);
FORCEPROP 3 LASTPIN (-5825 4075) SIG_NAME M_I_CPU0_SB_DQS_DN<8>
J 0
(-5815 4085);
DISPLAY 0.659574 (-5815 4085);
PAINT MONO (-5815 4085);
DISPLAY INVISIBLE (-5815 4085);
FORCEPROP 1 LASTPIN (-5825 4075) BN 8
J 2
(-5813 4083);
DISPLAY 0.489362 (-5813 4083);
PAINT GREEN (-5813 4083);
FORCEPROP 2 LAST CDS_LIB mstr_standard
J 2
(-5875 4075);
DISPLAY 0.723404 (-5875 4075);
PAINT MONO (-5875 4075);
DISPLAY INVISIBLE (-5875 4075);
FORCEPROP 1 LAST BODY_TYPE PLUMBING
J 2
(-5875 4125);
DISPLAY 0.872340 (-5875 4125);
PAINT GREEN (-5875 4125);
DISPLAY INVISIBLE (-5875 4125);
FORCEPROP 1 LAST HDL_TAP TRUE
J 2
(-6200 3950);
DISPLAY 0.872340 (-6200 3950);
DISPLAY INVISIBLE (-6200 3950);
FORCEPROP 1 LAST PATH I286
J 2
(-5873 4075);
DISPLAY 0.872340 (-5873 4075);
PAINT GREEN (-5873 4075);
DISPLAY INVISIBLE (-5873 4075);
FORCEADD TAP..1
R 2
(-5875 3975);
FORCEPROP 3 LASTPIN (-5825 3975) SIG_NAME M_I_CPU0_SB_DQS_DN<9>
J 0
(-5815 3985);
DISPLAY 0.659574 (-5815 3985);
PAINT MONO (-5815 3985);
DISPLAY INVISIBLE (-5815 3985);
FORCEPROP 1 LASTPIN (-5825 3975) BN 9
J 2
(-5813 3983);
DISPLAY 0.489362 (-5813 3983);
PAINT GREEN (-5813 3983);
FORCEPROP 2 LAST CDS_LIB mstr_standard
J 2
(-5875 3975);
DISPLAY 0.723404 (-5875 3975);
PAINT MONO (-5875 3975);
DISPLAY INVISIBLE (-5875 3975);
FORCEPROP 1 LAST BODY_TYPE PLUMBING
J 2
(-5875 4025);
DISPLAY 0.872340 (-5875 4025);
PAINT GREEN (-5875 4025);
DISPLAY INVISIBLE (-5875 4025);
FORCEPROP 1 LAST HDL_TAP TRUE
J 2
(-6200 3850);
DISPLAY 0.872340 (-6200 3850);
DISPLAY INVISIBLE (-6200 3850);
FORCEPROP 1 LAST PATH I287
J 2
(-5873 3975);
DISPLAY 0.872340 (-5873 3975);
PAINT GREEN (-5873 3975);
DISPLAY INVISIBLE (-5873 3975);
FORCEADD TAP..1
R 2
(-5875 3825);
FORCEPROP 3 LASTPIN (-5825 3825) SIG_NAME M_I_CPU0_SA_CA<0>
J 0
(-5815 3835);
DISPLAY 0.659574 (-5815 3835);
PAINT MONO (-5815 3835);
DISPLAY INVISIBLE (-5815 3835);
FORCEPROP 1 LASTPIN (-5825 3825) BN 0
J 2
(-5813 3833);
DISPLAY 0.489362 (-5813 3833);
PAINT GREEN (-5813 3833);
FORCEPROP 2 LAST CDS_LIB mstr_standard
J 0
(-5875 3825);
DISPLAY 0.723404 (-5875 3825);
PAINT MONO (-5875 3825);
DISPLAY INVISIBLE (-5875 3825);
FORCEPROP 1 LAST BODY_TYPE PLUMBING
J 2
(-5875 3875);
DISPLAY 0.872340 (-5875 3875);
PAINT GREEN (-5875 3875);
DISPLAY INVISIBLE (-5875 3875);
FORCEPROP 1 LAST HDL_TAP TRUE
J 2
(-6200 3700);
DISPLAY 0.872340 (-6200 3700);
DISPLAY INVISIBLE (-6200 3700);
FORCEPROP 1 LAST PATH I288
J 2
(-5873 3825);
DISPLAY 0.872340 (-5873 3825);
PAINT GREEN (-5873 3825);
DISPLAY INVISIBLE (-5873 3825);
FORCEADD TAP..1
R 2
(-5875 3775);
FORCEPROP 3 LASTPIN (-5825 3775) SIG_NAME M_I_CPU0_SA_CA<1>
J 0
(-5815 3785);
DISPLAY 0.659574 (-5815 3785);
PAINT MONO (-5815 3785);
DISPLAY INVISIBLE (-5815 3785);
FORCEPROP 1 LASTPIN (-5825 3775) BN 1
J 2
(-5813 3783);
DISPLAY 0.489362 (-5813 3783);
PAINT GREEN (-5813 3783);
FORCEPROP 2 LAST CDS_LIB mstr_standard
J 0
(-5875 3775);
DISPLAY 0.723404 (-5875 3775);
PAINT MONO (-5875 3775);
DISPLAY INVISIBLE (-5875 3775);
FORCEPROP 1 LAST BODY_TYPE PLUMBING
J 2
(-5875 3825);
DISPLAY 0.872340 (-5875 3825);
PAINT GREEN (-5875 3825);
DISPLAY INVISIBLE (-5875 3825);
FORCEPROP 1 LAST HDL_TAP TRUE
J 2
(-6200 3650);
DISPLAY 0.872340 (-6200 3650);
DISPLAY INVISIBLE (-6200 3650);
FORCEPROP 1 LAST PATH I289
J 2
(-5873 3775);
DISPLAY 0.872340 (-5873 3775);
PAINT GREEN (-5873 3775);
DISPLAY INVISIBLE (-5873 3775);
FORCEADD TAP..1
R 2
(-5875 3725);
FORCEPROP 3 LASTPIN (-5825 3725) SIG_NAME M_I_CPU0_SA_CA<2>
J 0
(-5815 3735);
DISPLAY 0.659574 (-5815 3735);
PAINT MONO (-5815 3735);
DISPLAY INVISIBLE (-5815 3735);
FORCEPROP 1 LASTPIN (-5825 3725) BN 2
J 2
(-5813 3733);
DISPLAY 0.489362 (-5813 3733);
PAINT GREEN (-5813 3733);
FORCEPROP 2 LAST CDS_LIB mstr_standard
J 0
(-5875 3725);
DISPLAY 0.723404 (-5875 3725);
PAINT MONO (-5875 3725);
DISPLAY INVISIBLE (-5875 3725);
FORCEPROP 1 LAST BODY_TYPE PLUMBING
J 2
(-5875 3775);
DISPLAY 0.872340 (-5875 3775);
PAINT GREEN (-5875 3775);
DISPLAY INVISIBLE (-5875 3775);
FORCEPROP 1 LAST HDL_TAP TRUE
J 2
(-6200 3600);
DISPLAY 0.872340 (-6200 3600);
DISPLAY INVISIBLE (-6200 3600);
FORCEPROP 1 LAST PATH I290
J 2
(-5873 3725);
DISPLAY 0.872340 (-5873 3725);
PAINT GREEN (-5873 3725);
DISPLAY INVISIBLE (-5873 3725);
FORCEADD TAP..1
R 2
(-5875 3625);
FORCEPROP 3 LASTPIN (-5825 3625) SIG_NAME M_I_CPU0_SA_CA<4>
J 0
(-5815 3635);
DISPLAY 0.659574 (-5815 3635);
PAINT MONO (-5815 3635);
DISPLAY INVISIBLE (-5815 3635);
FORCEPROP 1 LASTPIN (-5825 3625) BN 4
J 2
(-5813 3633);
DISPLAY 0.489362 (-5813 3633);
PAINT GREEN (-5813 3633);
FORCEPROP 2 LAST CDS_LIB mstr_standard
J 0
(-5875 3625);
DISPLAY 0.723404 (-5875 3625);
PAINT MONO (-5875 3625);
DISPLAY INVISIBLE (-5875 3625);
FORCEPROP 1 LAST BODY_TYPE PLUMBING
J 2
(-5875 3675);
DISPLAY 0.872340 (-5875 3675);
PAINT GREEN (-5875 3675);
DISPLAY INVISIBLE (-5875 3675);
FORCEPROP 1 LAST HDL_TAP TRUE
J 2
(-6200 3500);
DISPLAY 0.872340 (-6200 3500);
DISPLAY INVISIBLE (-6200 3500);
FORCEPROP 1 LAST PATH I291
J 2
(-5873 3625);
DISPLAY 0.872340 (-5873 3625);
PAINT GREEN (-5873 3625);
DISPLAY INVISIBLE (-5873 3625);
FORCEADD TAP..1
R 2
(-5875 3675);
FORCEPROP 3 LASTPIN (-5825 3675) SIG_NAME M_I_CPU0_SA_CA<3>
J 0
(-5815 3685);
DISPLAY 0.659574 (-5815 3685);
PAINT MONO (-5815 3685);
DISPLAY INVISIBLE (-5815 3685);
FORCEPROP 1 LASTPIN (-5825 3675) BN 3
J 2
(-5813 3683);
DISPLAY 0.489362 (-5813 3683);
PAINT GREEN (-5813 3683);
FORCEPROP 2 LAST CDS_LIB mstr_standard
J 0
(-5875 3675);
DISPLAY 0.723404 (-5875 3675);
PAINT MONO (-5875 3675);
DISPLAY INVISIBLE (-5875 3675);
FORCEPROP 1 LAST BODY_TYPE PLUMBING
J 2
(-5875 3725);
DISPLAY 0.872340 (-5875 3725);
PAINT GREEN (-5875 3725);
DISPLAY INVISIBLE (-5875 3725);
FORCEPROP 1 LAST HDL_TAP TRUE
J 2
(-6200 3550);
DISPLAY 0.872340 (-6200 3550);
DISPLAY INVISIBLE (-6200 3550);
FORCEPROP 1 LAST PATH I292
J 2
(-5873 3675);
DISPLAY 0.872340 (-5873 3675);
PAINT GREEN (-5873 3675);
DISPLAY INVISIBLE (-5873 3675);
FORCEADD TAP..1
R 2
(-5875 3525);
FORCEPROP 3 LASTPIN (-5825 3525) SIG_NAME M_I_CPU0_SA_CA<6>
J 0
(-5815 3535);
DISPLAY 0.659574 (-5815 3535);
PAINT MONO (-5815 3535);
DISPLAY INVISIBLE (-5815 3535);
FORCEPROP 1 LASTPIN (-5825 3525) BN 6
J 2
(-5813 3533);
DISPLAY 0.489362 (-5813 3533);
PAINT GREEN (-5813 3533);
FORCEPROP 2 LAST CDS_LIB mstr_standard
J 0
(-5875 3525);
DISPLAY 0.723404 (-5875 3525);
PAINT MONO (-5875 3525);
DISPLAY INVISIBLE (-5875 3525);
FORCEPROP 1 LAST BODY_TYPE PLUMBING
J 2
(-5875 3575);
DISPLAY 0.872340 (-5875 3575);
PAINT GREEN (-5875 3575);
DISPLAY INVISIBLE (-5875 3575);
FORCEPROP 1 LAST HDL_TAP TRUE
J 2
(-6200 3400);
DISPLAY 0.872340 (-6200 3400);
DISPLAY INVISIBLE (-6200 3400);
FORCEPROP 1 LAST PATH I293
J 2
(-5873 3525);
DISPLAY 0.872340 (-5873 3525);
PAINT GREEN (-5873 3525);
DISPLAY INVISIBLE (-5873 3525);
FORCEADD TAP..1
R 2
(-5875 3575);
FORCEPROP 3 LASTPIN (-5825 3575) SIG_NAME M_I_CPU0_SA_CA<5>
J 0
(-5815 3585);
DISPLAY 0.659574 (-5815 3585);
PAINT MONO (-5815 3585);
DISPLAY INVISIBLE (-5815 3585);
FORCEPROP 1 LASTPIN (-5825 3575) BN 5
J 2
(-5813 3583);
DISPLAY 0.489362 (-5813 3583);
PAINT GREEN (-5813 3583);
FORCEPROP 2 LAST CDS_LIB mstr_standard
J 0
(-5875 3575);
DISPLAY 0.723404 (-5875 3575);
PAINT MONO (-5875 3575);
DISPLAY INVISIBLE (-5875 3575);
FORCEPROP 1 LAST BODY_TYPE PLUMBING
J 2
(-5875 3625);
DISPLAY 0.872340 (-5875 3625);
PAINT GREEN (-5875 3625);
DISPLAY INVISIBLE (-5875 3625);
FORCEPROP 1 LAST HDL_TAP TRUE
J 2
(-6200 3450);
DISPLAY 0.872340 (-6200 3450);
DISPLAY INVISIBLE (-6200 3450);
FORCEPROP 1 LAST PATH I294
J 2
(-5873 3575);
DISPLAY 0.872340 (-5873 3575);
PAINT GREEN (-5873 3575);
DISPLAY INVISIBLE (-5873 3575);
FORCEADD TAP..1
R 2
(-5875 3375);
FORCEPROP 3 LASTPIN (-5825 3375) SIG_NAME M_I_CPU0_SB_CA<1>
J 0
(-5815 3385);
DISPLAY 0.659574 (-5815 3385);
PAINT MONO (-5815 3385);
DISPLAY INVISIBLE (-5815 3385);
FORCEPROP 1 LASTPIN (-5825 3375) BN 1
J 2
(-5813 3383);
DISPLAY 0.489362 (-5813 3383);
PAINT GREEN (-5813 3383);
FORCEPROP 2 LAST CDS_LIB mstr_standard
J 0
(-5875 3375);
DISPLAY 0.723404 (-5875 3375);
PAINT MONO (-5875 3375);
DISPLAY INVISIBLE (-5875 3375);
FORCEPROP 1 LAST BODY_TYPE PLUMBING
J 2
(-5875 3425);
DISPLAY 0.872340 (-5875 3425);
PAINT GREEN (-5875 3425);
DISPLAY INVISIBLE (-5875 3425);
FORCEPROP 1 LAST HDL_TAP TRUE
J 2
(-6200 3250);
DISPLAY 0.872340 (-6200 3250);
DISPLAY INVISIBLE (-6200 3250);
FORCEPROP 1 LAST PATH I295
J 2
(-5873 3375);
DISPLAY 0.872340 (-5873 3375);
PAINT GREEN (-5873 3375);
DISPLAY INVISIBLE (-5873 3375);
FORCEADD TAP..1
R 2
(-5875 3425);
FORCEPROP 3 LASTPIN (-5825 3425) SIG_NAME M_I_CPU0_SB_CA<0>
J 0
(-5815 3435);
DISPLAY 0.659574 (-5815 3435);
PAINT MONO (-5815 3435);
DISPLAY INVISIBLE (-5815 3435);
FORCEPROP 1 LASTPIN (-5825 3425) BN 0
J 2
(-5813 3433);
DISPLAY 0.489362 (-5813 3433);
PAINT GREEN (-5813 3433);
FORCEPROP 2 LAST CDS_LIB mstr_standard
J 0
(-5875 3425);
DISPLAY 0.723404 (-5875 3425);
PAINT MONO (-5875 3425);
DISPLAY INVISIBLE (-5875 3425);
FORCEPROP 1 LAST BODY_TYPE PLUMBING
J 2
(-5875 3475);
DISPLAY 0.872340 (-5875 3475);
PAINT GREEN (-5875 3475);
DISPLAY INVISIBLE (-5875 3475);
FORCEPROP 1 LAST HDL_TAP TRUE
J 2
(-6200 3300);
DISPLAY 0.872340 (-6200 3300);
DISPLAY INVISIBLE (-6200 3300);
FORCEPROP 1 LAST PATH I296
J 2
(-5873 3425);
DISPLAY 0.872340 (-5873 3425);
PAINT GREEN (-5873 3425);
DISPLAY INVISIBLE (-5873 3425);
FORCEADD TAP..1
R 2
(-5875 3325);
FORCEPROP 3 LASTPIN (-5825 3325) SIG_NAME M_I_CPU0_SB_CA<2>
J 0
(-5815 3335);
DISPLAY 0.659574 (-5815 3335);
PAINT MONO (-5815 3335);
DISPLAY INVISIBLE (-5815 3335);
FORCEPROP 1 LASTPIN (-5825 3325) BN 2
J 2
(-5813 3333);
DISPLAY 0.489362 (-5813 3333);
PAINT GREEN (-5813 3333);
FORCEPROP 2 LAST CDS_LIB mstr_standard
J 0
(-5875 3325);
DISPLAY 0.723404 (-5875 3325);
PAINT MONO (-5875 3325);
DISPLAY INVISIBLE (-5875 3325);
FORCEPROP 1 LAST BODY_TYPE PLUMBING
J 2
(-5875 3375);
DISPLAY 0.872340 (-5875 3375);
PAINT GREEN (-5875 3375);
DISPLAY INVISIBLE (-5875 3375);
FORCEPROP 1 LAST HDL_TAP TRUE
J 2
(-6200 3200);
DISPLAY 0.872340 (-6200 3200);
DISPLAY INVISIBLE (-6200 3200);
FORCEPROP 1 LAST PATH I297
J 2
(-5873 3325);
DISPLAY 0.872340 (-5873 3325);
PAINT GREEN (-5873 3325);
DISPLAY INVISIBLE (-5873 3325);
FORCEADD TAP..1
R 2
(-5875 3275);
FORCEPROP 3 LASTPIN (-5825 3275) SIG_NAME M_I_CPU0_SB_CA<3>
J 0
(-5815 3285);
DISPLAY 0.659574 (-5815 3285);
PAINT MONO (-5815 3285);
DISPLAY INVISIBLE (-5815 3285);
FORCEPROP 1 LASTPIN (-5825 3275) BN 3
J 2
(-5813 3283);
DISPLAY 0.489362 (-5813 3283);
PAINT GREEN (-5813 3283);
FORCEPROP 2 LAST CDS_LIB mstr_standard
J 0
(-5875 3275);
DISPLAY 0.723404 (-5875 3275);
PAINT MONO (-5875 3275);
DISPLAY INVISIBLE (-5875 3275);
FORCEPROP 1 LAST BODY_TYPE PLUMBING
J 2
(-5875 3325);
DISPLAY 0.872340 (-5875 3325);
PAINT GREEN (-5875 3325);
DISPLAY INVISIBLE (-5875 3325);
FORCEPROP 1 LAST HDL_TAP TRUE
J 2
(-6200 3150);
DISPLAY 0.872340 (-6200 3150);
DISPLAY INVISIBLE (-6200 3150);
FORCEPROP 1 LAST PATH I298
J 2
(-5873 3275);
DISPLAY 0.872340 (-5873 3275);
PAINT GREEN (-5873 3275);
DISPLAY INVISIBLE (-5873 3275);
FORCEADD TAP..1
R 2
(-5875 3225);
FORCEPROP 3 LASTPIN (-5825 3225) SIG_NAME M_I_CPU0_SB_CA<4>
J 0
(-5815 3235);
DISPLAY 0.659574 (-5815 3235);
PAINT MONO (-5815 3235);
DISPLAY INVISIBLE (-5815 3235);
FORCEPROP 1 LASTPIN (-5825 3225) BN 4
J 2
(-5813 3233);
DISPLAY 0.489362 (-5813 3233);
PAINT GREEN (-5813 3233);
FORCEPROP 2 LAST CDS_LIB mstr_standard
J 0
(-5875 3225);
DISPLAY 0.723404 (-5875 3225);
PAINT MONO (-5875 3225);
DISPLAY INVISIBLE (-5875 3225);
FORCEPROP 1 LAST BODY_TYPE PLUMBING
J 2
(-5875 3275);
DISPLAY 0.872340 (-5875 3275);
PAINT GREEN (-5875 3275);
DISPLAY INVISIBLE (-5875 3275);
FORCEPROP 1 LAST HDL_TAP TRUE
J 2
(-6200 3100);
DISPLAY 0.872340 (-6200 3100);
DISPLAY INVISIBLE (-6200 3100);
FORCEPROP 1 LAST PATH I299
J 2
(-5873 3225);
DISPLAY 0.872340 (-5873 3225);
PAINT GREEN (-5873 3225);
DISPLAY INVISIBLE (-5873 3225);
FORCEADD TAP..1
R 2
(-5875 3125);
FORCEPROP 3 LASTPIN (-5825 3125) SIG_NAME M_I_CPU0_SB_CA<6>
J 0
(-5815 3135);
DISPLAY 0.659574 (-5815 3135);
PAINT MONO (-5815 3135);
DISPLAY INVISIBLE (-5815 3135);
FORCEPROP 1 LASTPIN (-5825 3125) BN 6
J 2
(-5813 3133);
DISPLAY 0.489362 (-5813 3133);
PAINT GREEN (-5813 3133);
FORCEPROP 2 LAST CDS_LIB mstr_standard
J 0
(-5875 3125);
DISPLAY 0.723404 (-5875 3125);
PAINT MONO (-5875 3125);
DISPLAY INVISIBLE (-5875 3125);
FORCEPROP 1 LAST BODY_TYPE PLUMBING
J 2
(-5875 3175);
DISPLAY 0.872340 (-5875 3175);
PAINT GREEN (-5875 3175);
DISPLAY INVISIBLE (-5875 3175);
FORCEPROP 1 LAST HDL_TAP TRUE
J 2
(-6200 3000);
DISPLAY 0.872340 (-6200 3000);
DISPLAY INVISIBLE (-6200 3000);
FORCEPROP 1 LAST PATH I300
J 2
(-5873 3125);
DISPLAY 0.872340 (-5873 3125);
PAINT GREEN (-5873 3125);
DISPLAY INVISIBLE (-5873 3125);
FORCEADD TAP..1
R 2
(-5875 3175);
FORCEPROP 3 LASTPIN (-5825 3175) SIG_NAME M_I_CPU0_SB_CA<5>
J 0
(-5815 3185);
DISPLAY 0.659574 (-5815 3185);
PAINT MONO (-5815 3185);
DISPLAY INVISIBLE (-5815 3185);
FORCEPROP 1 LASTPIN (-5825 3175) BN 5
J 2
(-5813 3183);
DISPLAY 0.489362 (-5813 3183);
PAINT GREEN (-5813 3183);
FORCEPROP 2 LAST CDS_LIB mstr_standard
J 0
(-5875 3175);
DISPLAY 0.723404 (-5875 3175);
PAINT MONO (-5875 3175);
DISPLAY INVISIBLE (-5875 3175);
FORCEPROP 1 LAST BODY_TYPE PLUMBING
J 2
(-5875 3225);
DISPLAY 0.872340 (-5875 3225);
PAINT GREEN (-5875 3225);
DISPLAY INVISIBLE (-5875 3225);
FORCEPROP 1 LAST HDL_TAP TRUE
J 2
(-6200 3050);
DISPLAY 0.872340 (-6200 3050);
DISPLAY INVISIBLE (-6200 3050);
FORCEPROP 1 LAST PATH I301
J 2
(-5873 3175);
DISPLAY 0.872340 (-5873 3175);
PAINT GREEN (-5873 3175);
DISPLAY INVISIBLE (-5873 3175);
FORCEADD OFFPAGE..2
R 2
(-6475 3850);
FORCEPROP 2 LAST $XR0 94 
J 0
(-6729 3850);
DISPLAY 0.638298 (-6729 3850);
PAINT MONO (-6729 3850);
FORCEPROP 2 LAST CDS_LIB standard
J 0
(-6475 3850);
DISPLAY INVISIBLE (-6475 3850);
FORCEPROP 1 LAST OFFPAGE TRUE
J 2
(-6800 3725);
DISPLAY 0.872340 (-6800 3725);
PAINT GREEN (-6800 3725);
DISPLAY INVISIBLE (-6800 3725);
FORCEPROP 1 LAST COMMENT_BODY TRUE
J 2
(-6430 3755);
DISPLAY 0.872340 (-6430 3755);
PAINT GREEN (-6430 3755);
DISPLAY INVISIBLE (-6430 3755);
FORCEPROP 2 LAST PATH I302
J 0
(-6750 3900);
DISPLAY 1.021277 (-6750 3900);
DISPLAY INVISIBLE (-6750 3900);
FORCEADD OFFPAGE..2
R 2
(-6475 3450);
FORCEPROP 2 LAST $XR0 94 
J 0
(-6729 3450);
DISPLAY 0.638298 (-6729 3450);
PAINT MONO (-6729 3450);
FORCEPROP 2 LAST CDS_LIB standard
J 0
(-6475 3450);
DISPLAY INVISIBLE (-6475 3450);
FORCEPROP 1 LAST OFFPAGE TRUE
J 2
(-6800 3325);
DISPLAY 0.872340 (-6800 3325);
PAINT GREEN (-6800 3325);
DISPLAY INVISIBLE (-6800 3325);
FORCEPROP 1 LAST COMMENT_BODY TRUE
J 2
(-6430 3355);
DISPLAY 0.872340 (-6430 3355);
PAINT GREEN (-6430 3355);
DISPLAY INVISIBLE (-6430 3355);
FORCEPROP 2 LAST PATH I303
J 0
(-6750 3500);
DISPLAY 1.021277 (-6750 3500);
DISPLAY INVISIBLE (-6750 3500);
FORCEADD OFFPAGE..2
R 2
(-6475 2975);
FORCEPROP 2 LAST $XR0 94 
J 0
(-6729 2975);
DISPLAY 0.638298 (-6729 2975);
PAINT MONO (-6729 2975);
FORCEPROP 2 LAST CDS_LIB standard
J 0
(-6475 2975);
DISPLAY INVISIBLE (-6475 2975);
FORCEPROP 1 LAST OFFPAGE TRUE
J 2
(-6800 2850);
DISPLAY 0.872340 (-6800 2850);
PAINT GREEN (-6800 2850);
DISPLAY INVISIBLE (-6800 2850);
FORCEPROP 1 LAST COMMENT_BODY TRUE
J 2
(-6430 2880);
DISPLAY 0.872340 (-6430 2880);
PAINT GREEN (-6430 2880);
DISPLAY INVISIBLE (-6430 2880);
FORCEPROP 2 LAST PATH I304
J 0
(-6750 3025);
DISPLAY 1.021277 (-6750 3025);
DISPLAY INVISIBLE (-6750 3025);
FORCEADD OFFPAGE..2
R 2
(-6475 2925);
FORCEPROP 2 LAST $XR0 94 
J 0
(-6729 2925);
DISPLAY 0.638298 (-6729 2925);
PAINT MONO (-6729 2925);
FORCEPROP 2 LAST CDS_LIB standard
J 0
(-6475 2925);
DISPLAY INVISIBLE (-6475 2925);
FORCEPROP 1 LAST OFFPAGE TRUE
J 2
(-6800 2800);
DISPLAY 0.872340 (-6800 2800);
PAINT GREEN (-6800 2800);
DISPLAY INVISIBLE (-6800 2800);
FORCEPROP 1 LAST COMMENT_BODY TRUE
J 2
(-6430 2830);
DISPLAY 0.872340 (-6430 2830);
PAINT GREEN (-6430 2830);
DISPLAY INVISIBLE (-6430 2830);
FORCEPROP 2 LAST PATH I305
J 0
(-6750 2975);
DISPLAY 1.021277 (-6750 2975);
DISPLAY INVISIBLE (-6750 2975);
FORCEADD OFFPAGE..2
R 2
(-6475 2825);
FORCEPROP 2 LAST $XR0 94 
J 0
(-6729 2825);
DISPLAY 0.638298 (-6729 2825);
PAINT MONO (-6729 2825);
FORCEPROP 2 LAST CDS_LIB standard
J 0
(-6475 2825);
DISPLAY INVISIBLE (-6475 2825);
FORCEPROP 1 LAST OFFPAGE TRUE
J 2
(-6800 2700);
DISPLAY 0.872340 (-6800 2700);
PAINT GREEN (-6800 2700);
DISPLAY INVISIBLE (-6800 2700);
FORCEPROP 1 LAST COMMENT_BODY TRUE
J 2
(-6430 2730);
DISPLAY 0.872340 (-6430 2730);
PAINT GREEN (-6430 2730);
DISPLAY INVISIBLE (-6430 2730);
FORCEPROP 2 LAST PATH I306
J 0
(-6750 2875);
DISPLAY 1.021277 (-6750 2875);
DISPLAY INVISIBLE (-6750 2875);
FORCEADD OFFPAGE..2
R 2
(-6475 2775);
FORCEPROP 2 LAST $XR0 94 
J 0
(-6729 2775);
DISPLAY 0.638298 (-6729 2775);
PAINT MONO (-6729 2775);
FORCEPROP 2 LAST CDS_LIB standard
J 0
(-6475 2775);
DISPLAY INVISIBLE (-6475 2775);
FORCEPROP 1 LAST OFFPAGE TRUE
J 2
(-6800 2650);
DISPLAY 0.872340 (-6800 2650);
PAINT GREEN (-6800 2650);
DISPLAY INVISIBLE (-6800 2650);
FORCEPROP 1 LAST COMMENT_BODY TRUE
J 2
(-6430 2680);
DISPLAY 0.872340 (-6430 2680);
PAINT GREEN (-6430 2680);
DISPLAY INVISIBLE (-6430 2680);
FORCEPROP 2 LAST PATH I307
J 0
(-6750 2825);
DISPLAY 1.021277 (-6750 2825);
DISPLAY INVISIBLE (-6750 2825);
FORCEADD OFFPAGE..1
(-6475 2675);
FORCEPROP 2 LAST $XR0 94 
J 0
(-6726 2675);
DISPLAY 0.638298 (-6726 2675);
PAINT MONO (-6726 2675);
FORCEPROP 2 LAST CDS_LIB standard
J 0
(-6475 2675);
DISPLAY INVISIBLE (-6475 2675);
FORCEPROP 1 LAST OFFPAGE TRUE
J 0
(-6150 2550);
DISPLAY 0.872340 (-6150 2550);
PAINT GREEN (-6150 2550);
DISPLAY INVISIBLE (-6150 2550);
FORCEPROP 1 LAST COMMENT_BODY TRUE
J 0
(-6350 2575);
DISPLAY 0.872340 (-6350 2575);
PAINT GREEN (-6350 2575);
DISPLAY INVISIBLE (-6350 2575);
FORCEPROP 2 LAST PATH I308
J 0
(-6725 2725);
DISPLAY 1.021277 (-6725 2725);
DISPLAY INVISIBLE (-6725 2725);
FORCEADD OFFPAGE..5
(-6475 2575);
FORCEPROP 2 LAST $XR0 94 
J 0
(-6729 2575);
DISPLAY 0.638298 (-6729 2575);
PAINT MONO (-6729 2575);
FORCEPROP 2 LAST CDS_LIB mstr_standard
J 0
(-6475 2575);
DISPLAY INVISIBLE (-6475 2575);
FORCEPROP 1 LAST OFFPAGE TRUE
J 0
(-6150 2450);
DISPLAY 0.872340 (-6150 2450);
PAINT GREEN (-6150 2450);
DISPLAY INVISIBLE (-6150 2450);
FORCEPROP 1 LAST COMMENT_BODY TRUE
J 0
(-6375 2500);
DISPLAY 0.872340 (-6375 2500);
PAINT GREEN (-6375 2500);
DISPLAY INVISIBLE (-6375 2500);
FORCEPROP 2 LAST PATH I309
J 0
(-6750 2625);
DISPLAY 1.021277 (-6750 2625);
DISPLAY INVISIBLE (-6750 2625);
FORCEADD OFFPAGE..2
R 2
(-6475 2475);
FORCEPROP 2 LAST $XR0 94 
J 0
(-6729 2475);
DISPLAY 0.638298 (-6729 2475);
PAINT MONO (-6729 2475);
FORCEPROP 2 LAST CDS_LIB standard
J 0
(-6475 2475);
DISPLAY INVISIBLE (-6475 2475);
FORCEPROP 1 LAST OFFPAGE TRUE
J 2
(-6800 2350);
DISPLAY 0.872340 (-6800 2350);
PAINT GREEN (-6800 2350);
DISPLAY INVISIBLE (-6800 2350);
FORCEPROP 1 LAST COMMENT_BODY TRUE
J 2
(-6430 2380);
DISPLAY 0.872340 (-6430 2380);
PAINT GREEN (-6430 2380);
DISPLAY INVISIBLE (-6430 2380);
FORCEPROP 2 LAST PATH I310
J 0
(-6750 2525);
DISPLAY 1.021277 (-6750 2525);
DISPLAY INVISIBLE (-6750 2525);
FORCEADD OFFPAGE..2
R 2
(-6475 2425);
FORCEPROP 2 LAST $XR0 94 
J 0
(-6729 2425);
DISPLAY 0.638298 (-6729 2425);
PAINT MONO (-6729 2425);
FORCEPROP 2 LAST CDS_LIB standard
J 0
(-6475 2425);
DISPLAY INVISIBLE (-6475 2425);
FORCEPROP 1 LAST OFFPAGE TRUE
J 2
(-6800 2300);
DISPLAY 0.872340 (-6800 2300);
PAINT GREEN (-6800 2300);
DISPLAY INVISIBLE (-6800 2300);
FORCEPROP 1 LAST COMMENT_BODY TRUE
J 2
(-6430 2330);
DISPLAY 0.872340 (-6430 2330);
PAINT GREEN (-6430 2330);
DISPLAY INVISIBLE (-6430 2330);
FORCEPROP 2 LAST PATH I311
J 0
(-6750 2475);
DISPLAY 1.021277 (-6750 2475);
DISPLAY INVISIBLE (-6750 2475);
FORCEADD OFFPAGE..1
(-6475 2325);
FORCEPROP 2 LAST $XR0 94 
J 0
(-6726 2325);
DISPLAY 0.638298 (-6726 2325);
PAINT MONO (-6726 2325);
FORCEPROP 2 LAST CDS_LIB standard
J 0
(-6475 2325);
DISPLAY INVISIBLE (-6475 2325);
FORCEPROP 1 LAST OFFPAGE TRUE
J 0
(-6150 2200);
DISPLAY 0.872340 (-6150 2200);
PAINT GREEN (-6150 2200);
DISPLAY INVISIBLE (-6150 2200);
FORCEPROP 1 LAST COMMENT_BODY TRUE
J 0
(-6350 2225);
DISPLAY 0.872340 (-6350 2225);
PAINT GREEN (-6350 2225);
DISPLAY INVISIBLE (-6350 2225);
FORCEPROP 2 LAST PATH I312
J 0
(-6725 2375);
DISPLAY 1.021277 (-6725 2375);
DISPLAY INVISIBLE (-6725 2375);
FORCEADD OFFPAGE..5
(-6475 2225);
FORCEPROP 2 LAST $XR0 94 
J 0
(-6729 2225);
DISPLAY 0.638298 (-6729 2225);
PAINT MONO (-6729 2225);
FORCEPROP 2 LAST CDS_LIB standard
J 0
(-6475 2225);
DISPLAY INVISIBLE (-6475 2225);
FORCEPROP 1 LAST OFFPAGE TRUE
J 0
(-6150 2100);
DISPLAY 0.872340 (-6150 2100);
PAINT GREEN (-6150 2100);
DISPLAY INVISIBLE (-6150 2100);
FORCEPROP 1 LAST COMMENT_BODY TRUE
J 0
(-6375 2150);
DISPLAY 0.872340 (-6375 2150);
PAINT GREEN (-6375 2150);
DISPLAY INVISIBLE (-6375 2150);
FORCEPROP 2 LAST PATH I313
J 0
(-6750 2275);
DISPLAY 1.021277 (-6750 2275);
DISPLAY INVISIBLE (-6750 2275);
FORCEADD Q_RES..1
(-6800 2125);
FORCEPROP 1 LAST LOCATION R383
J 0
(-7125 2125);
DISPLAY 0.489362 (-7125 2125);
PAINT SKYBLUE (-7125 2125);
FORCEPROP 0 LAST $SEC 1
J 0
(-6975 2175);
DISPLAY 0.680851 (-6975 2175);
PAINT MONO (-6975 2175);
DISPLAY INVISIBLE (-6975 2175);
FORCEPROP 0 LAST CDS_SEC 1
J 0
(-6975 2175);
DISPLAY 1.021277 (-6975 2175);
DISPLAY INVISIBLE (-6975 2175);
FORCEPROP 1 LASTPIN (-6900 2125) $PN 1
J 0
(-6888 2137);
DISPLAY 0.489362 (-6888 2137);
PAINT MONO (-6888 2137);
FORCEPROP 1 LASTPIN (-6700 2125) $PN 2
J 0
(-6738 2137);
DISPLAY 0.489362 (-6738 2137);
PAINT MONO (-6738 2137);
FORCEPROP 1 LAST PACK_TYPE 0402LF
J 0
(-7125 2100);
DISPLAY 0.489362 (-7125 2100);
PAINT SKYBLUE (-7125 2100);
FORCEPROP 1 LAST TOLERANCE 1%
J 0
(-6525 2125);
DISPLAY 0.489362 (-6525 2125);
PAINT SKYBLUE (-6525 2125);
FORCEPROP 1 LAST VALUE 15
J 2
(-6475 2125);
DISPLAY 0.489362 (-6475 2125);
PAINT SKYBLUE (-6475 2125);
FORCEPROP 1 LAST MATERIAL CHIP
J 0
(-6925 2250);
DISPLAY 0.638298 (-6925 2250);
PAINT SKYBLUE (-6925 2250);
DISPLAY INVISIBLE (-6925 2250);
FORCEPROP 1 LAST WATTAGE 1/16W
J 2
(-6575 2250);
DISPLAY 0.638298 (-6575 2250);
PAINT SKYBLUE (-6575 2250);
DISPLAY INVISIBLE (-6575 2250);
FORCEPROP 2 LAST CDS_LIB pure_quanta
J 0
(-6800 2125);
DISPLAY INVISIBLE (-6800 2125);
FORCEPROP 1 LAST PATH I314
J 0
(-6850 2275);
DISPLAY 0.978723 (-6850 2275);
PAINT WHITE (-6850 2275);
DISPLAY INVISIBLE (-6850 2275);
FORCEPROP 1 LAST PART_NUMBER CS01502FB03
J 0
(-6700 2100);
DISPLAY 0.489362 (-6700 2100);
PAINT SKYBLUE (-6700 2100);
DISPLAY INVISIBLE (-6700 2100);
FORCEADD OFFPAGE..1
(-7675 2125);
FORCEPROP 2 LAST $XR0 94 
J 0
(-7926 2125);
DISPLAY 0.638298 (-7926 2125);
PAINT MONO (-7926 2125);
FORCEPROP 2 LAST CDS_LIB mstr_standard
J 0
(-7675 2125);
DISPLAY INVISIBLE (-7675 2125);
FORCEPROP 1 LAST OFFPAGE TRUE
J 0
(-7350 2000);
DISPLAY 0.872340 (-7350 2000);
PAINT GREEN (-7350 2000);
DISPLAY INVISIBLE (-7350 2000);
FORCEPROP 1 LAST COMMENT_BODY TRUE
J 0
(-7550 2025);
DISPLAY 0.872340 (-7550 2025);
PAINT GREEN (-7550 2025);
DISPLAY INVISIBLE (-7550 2025);
FORCEPROP 2 LAST PATH I315
J 0
(-7950 2175);
DISPLAY 1.021277 (-7950 2175);
DISPLAY INVISIBLE (-7950 2175);
FORCEADD OFFPAGE..5
(-6475 2025);
FORCEPROP 2 LAST $XR0 94 
J 0
(-6729 2025);
DISPLAY 0.638298 (-6729 2025);
PAINT MONO (-6729 2025);
FORCEPROP 2 LAST CDS_LIB standard
J 0
(-6475 2025);
DISPLAY INVISIBLE (-6475 2025);
FORCEPROP 1 LAST OFFPAGE TRUE
J 0
(-6150 1900);
DISPLAY 0.872340 (-6150 1900);
PAINT GREEN (-6150 1900);
DISPLAY INVISIBLE (-6150 1900);
FORCEPROP 1 LAST COMMENT_BODY TRUE
J 0
(-6375 1950);
DISPLAY 0.872340 (-6375 1950);
PAINT GREEN (-6375 1950);
DISPLAY INVISIBLE (-6375 1950);
FORCEPROP 2 LAST PATH I316
J 0
(-6750 2075);
DISPLAY 1.021277 (-6750 2075);
DISPLAY INVISIBLE (-6750 2075);
FORCEADD QUANTA_TITLE_BLOCK_C..1
(0 0);
FORCEPROP 0 LAST CDS_CON_LAST_MODIFIED Thu Sep 14 16:11:50 2023
J 0
(-1885 15);
DISPLAY INVISIBLE (-1885 15);
FORCEPROP 1 LAST CUSTOM_TXT_CDS <CON_LAST_MODIFIED>
J 0
(-1885 15);
DISPLAY 0.978723 (-1885 15);
FORCEPROP 2 LAST CUSTOM_TXT_CDS <XR_PAGE_TITLE>
J 0
(-7890 5250);
DISPLAY 0.638298 (-7890 5250);
PAINT PINK (-7890 5250);
DISPLAY INVISIBLE (-7890 5250);
FORCEPROP 1 LAST CUSTOM_TXT_CDS <NAME_2>
J 0
(-3175 50);
FORCEPROP 1 LAST CUSTOM_TXT_CDS <NAME_1>
J 0
(-3175 175);
FORCEPROP 1 LAST CUSTOM_TXT_CDS <Q_NUMBER>
J 0
(-1403 103);
DISPLAY 1.212766 (-1403 103);
FORCEPROP 1 LAST CUSTOM_TXT_CDS <Q_PROJ>
J 0
(-2382 102);
DISPLAY 1.212766 (-2382 102);
FORCEPROP 1 LAST CUSTOM_TXT_CDS <Q_REV>
J 0
(-184 103);
DISPLAY 1.212766 (-184 103);
FORCEPROP 1 LAST CUSTOM_TXT_CDS <CON_PAGE_NUM> OF <CON_TOTAL_PAGES>
J 0
(-446 18);
DISPLAY 0.978723 (-446 18);
FORCEPROP 1 LAST Q_TITLE CPU0 DDR CHI
J 0
(-9325 25);
DISPLAY 2.446809 (-9325 25);
PAINT GREEN (-9325 25);
FORCEPROP 2 LAST PAGE_BORDER TRUE
J 0
(-7890 5250);
DISPLAY 0.638298 (-7890 5250);
PAINT PINK (-7890 5250);
DISPLAY INVISIBLE (-7890 5250);
FORCEPROP 2 LAST CDS_LIB pure_quanta
J 0
(0 0);
DISPLAY INVISIBLE (0 0);
FORCEPROP 1 LAST CDS_LMAN_SYM_OUTLINE -9475,6775,100,-125
J 0
(0 0);
DISPLAY 0.468085 (0 0);
PAINT GREEN (0 0);
DISPLAY INVISIBLE (0 0);
FORCEPROP 2 LAST CDS_XR_PAGE_TITLE CR-18 : @T6G_MB_LIB.T6G(SCH_1):PAGE18
J 0
(-7890 5250);
DISPLAY 0.638298 (-7890 5250);
PAINT PINK (-7890 5250);
DISPLAY INVISIBLE (-7890 5250);
FORCEPROP 1 LAST Q_DEPT BU9
J 1
(-3763 49);
DISPLAY 1.957447 (-3763 49);
PAINT GREEN (-3763 49);
DISPLAY INVISIBLE (-3763 49);
FORCEPROP 1 LAST COMMENT_BODY TRUE
J 0
(12 -13);
DISPLAY 0.978723 (12 -13);
PAINT GREEN (12 -13);
DISPLAY INVISIBLE (12 -13);
FORCEADD CAD_NOTE..1
(-7600 2425);
FORCEPROP 0 LAST L1 R1948 PLACE CLOSE TO CPU < 25MM
J 0
(-7750 2300);
DISPLAY 0.617021 (-7750 2300);
PAINT WHITE (-7750 2300);
FORCEPROP 2 LAST CDS_LIB pure_quanta_power
J 0
(-7600 2425);
DISPLAY INVISIBLE (-7600 2425);
FORCEPROP 1 LAST COMMENT_BODY TRUE
J 0
(-7575 2525);
DISPLAY 0.574468 (-7575 2525);
PAINT WHITE (-7575 2525);
DISPLAY INVISIBLE (-7575 2525);
WIRE 17 -1 (-3200 5750)(-3200 5700);
WIRE 17 -1 (-3200 5800)(-3200 5750);
WIRE 17 -1 (-3200 5700)(-3200 5650);
WIRE 17 -1 (-3200 5650)(-3200 5550);
WIRE 17 -1 (-3200 5850)(-3200 5800);
WIRE 17 -1 (-3200 5900)(-3200 5850);
WIRE 17 -1 (-3200 5550)(-3200 5500);
WIRE 17 -1 (-3200 5500)(-3200 5450);
WIRE 17 -1 (-3200 5950)(-3200 5900);
WIRE 17 -1 (-3200 6000)(-3200 5950);
WIRE 17 -1 (-3200 5450)(-3200 5400);
WIRE 17 -1 (-3200 5400)(-3200 5350);
WIRE 17 -1 (-3200 6000)(-2575 6000);
FORCEPROP 2 LAST SIG_NAME M_I_CPU0_SA_DQ<31:0>
J 2
(-2635 6010);
DISPLAY 0.489362 (-2635 6010);
WIRE 17 -1 (-3200 5350)(-3200 5300);
WIRE 17 -1 (-3200 5300)(-3200 5250);
WIRE 17 -1 (-3200 5250)(-3200 5200);
WIRE 17 -1 (-3200 5100)(-3200 5200);
WIRE 17 -1 (-3200 5050)(-3200 5100);
WIRE 17 -1 (-3200 5000)(-3200 5050);
WIRE 17 -1 (-3200 4950)(-3200 5000);
WIRE 17 -1 (-3200 4950)(-3200 4900);
WIRE 17 -1 (-3200 4900)(-3200 4850);
WIRE 17 -1 (-3200 4850)(-3200 4800);
WIRE 17 -1 (-3200 4800)(-3200 4750);
WIRE 17 -1 (-3200 4750)(-3200 4650);
WIRE 17 -1 (-3200 4650)(-3200 4600);
WIRE 17 -1 (-3200 4600)(-3200 4550);
WIRE 17 -1 (-3200 4550)(-3200 4500);
WIRE 17 -1 (-3200 4450)(-3200 4500);
WIRE 17 -1 (-3200 4400)(-3200 4450);
WIRE 17 -1 (-3200 4350)(-3200 4400);
WIRE 17 -1 (-3200 4300)(-3200 4350);
WIRE 17 -1 (-3200 4200)(-2575 4200);
FORCEPROP 2 LAST SIG_NAME M_I_CPU0_SB_DQ<31:0>
J 2
(-2635 4210);
DISPLAY 0.489362 (-2635 4210);
WIRE 17 -1 (-3200 4200)(-3200 4150);
WIRE 17 -1 (-3200 3600)(-3200 3550);
WIRE 17 -1 (-3200 3650)(-3200 3600);
WIRE 17 -1 (-3200 3550)(-3200 3500);
WIRE 17 -1 (-3200 3500)(-3200 3450);
WIRE 17 -1 (-3200 3700)(-3200 3650);
WIRE 17 -1 (-3200 3750)(-3200 3700);
WIRE 17 -1 (-3200 3450)(-3200 3400);
WIRE 17 -1 (-3200 3300)(-3200 3400);
WIRE 17 -1 (-3200 3850)(-3200 3750);
WIRE 17 -1 (-3200 3900)(-3200 3850);
WIRE 17 -1 (-3200 3250)(-3200 3300);
WIRE 17 -1 (-3200 3200)(-3200 3250);
WIRE 17 -1 (-3200 3950)(-3200 3900);
WIRE 17 -1 (-3200 4000)(-3200 3950);
WIRE 17 -1 (-3200 3150)(-3200 3200);
WIRE 17 -1 (-3200 3150)(-3200 3100);
WIRE 17 -1 (-3200 4050)(-3200 4000);
WIRE 17 -1 (-3200 4100)(-3200 4050);
WIRE 17 -1 (-3200 3100)(-3200 3050);
WIRE 17 -1 (-3200 3050)(-3200 3000);
WIRE 17 -1 (-3200 4150)(-3200 4100);
WIRE 17 -1 (-3200 3000)(-3200 2950);
WIRE 17 -1 (-3200 2950)(-3200 2850);
WIRE 17 -1 (-3200 2850)(-3200 2800);
WIRE 17 -1 (-3200 2800)(-3200 2750);
WIRE 17 -1 (-3200 2750)(-3200 2700);
WIRE 17 -1 (-3200 2650)(-3200 2700);
WIRE 17 -1 (-3200 2600)(-3200 2650);
WIRE 17 -1 (-3200 2550)(-3200 2600);
WIRE 17 -1 (-3200 2500)(-3200 2550);
WIRE 17 -1 (-3200 2400)(-3200 2425);
WIRE 17 -1 (-3200 2400)(-3200 2350);
WIRE 17 -1 (-3200 2425)(-2700 2425);
FORCEPROP 2 LAST SIG_NAME M_I_CPU0_SA_CB<7:0>
J 2
(-2700 2435);
DISPLAY 0.489362 (-2700 2435);
WIRE 17 -1 (-3200 2300)(-3200 2350);
WIRE 17 -1 (-3200 2300)(-3200 2250);
WIRE 17 -1 (-3200 2200)(-3200 2250);
WIRE 17 -1 (-3200 2150)(-3200 2200);
WIRE 17 -1 (-3200 2100)(-3200 2150);
WIRE 17 -1 (-3200 2050)(-3200 2100);
WIRE 17 -1 (-3200 1850)(-3200 1800);
WIRE 17 -1 (-3200 1850)(-3200 1900);
WIRE 17 -1 (-3200 1750)(-3200 1800);
WIRE 17 -1 (-3200 1700)(-3200 1750);
WIRE 17 -1 (-3200 1950)(-3200 1900);
WIRE 17 -1 (-3200 1950)(-3200 1975);
WIRE 17 -1 (-3200 1650)(-3200 1700);
WIRE 17 -1 (-3200 1600)(-3200 1650);
WIRE 17 -1 (-3200 1975)(-2700 1975);
FORCEPROP 2 LAST SIG_NAME M_I_CPU0_SB_CB<7:0>
J 2
(-2700 1985);
DISPLAY 0.489362 (-2700 1985);
WIRE 17 -1 (-5725 6000)(-5725 5900);
WIRE 17 -1 (-5725 6000)(-6525 6000);
FORCEPROP 2 LAST SIG_NAME M_I_CPU0_SA_DQS_DP<9:0>
J 2
(-5960 6010);
DISPLAY 0.489362 (-5960 6010);
WIRE 17 -1 (-5725 5900)(-5725 5800);
WIRE 17 -1 (-5725 5800)(-5725 5700);
WIRE 17 -1 (-5725 5700)(-5725 5600);
WIRE 17 -1 (-5725 5500)(-5725 5600);
WIRE 17 -1 (-5725 5400)(-5725 5500);
WIRE 17 -1 (-5725 5300)(-5725 5400);
WIRE 17 -1 (-5725 5300)(-5725 5200);
WIRE 17 -1 (-5725 5200)(-5725 5100);
WIRE 17 -1 (-5925 5450)(-5925 5550);
WIRE 17 -1 (-5925 5350)(-5925 5450);
WIRE 17 -1 (-5925 5650)(-5925 5550);
WIRE 17 -1 (-5925 5750)(-5925 5650);
WIRE 17 -1 (-5925 5250)(-5925 5350);
WIRE 17 -1 (-5925 5250)(-5925 5150);
WIRE 17 -1 (-5925 5850)(-5925 5750);
WIRE 17 -1 (-5925 5950)(-5925 5850);
FORCEPROP 2 LAST SIG_NAME M_I_CPU0_SA_DQS_DN<9:0>
J 2
(-5960 5960);
DISPLAY 0.489362 (-5960 5960);
WIRE 17 -1 (-5925 5150)(-5925 5050);
WIRE 17 -1 (-5725 4950)(-5725 4850);
WIRE 17 -1 (-5725 4950)(-6525 4950);
FORCEPROP 2 LAST SIG_NAME M_I_CPU0_SB_DQS_DP<9:0>
J 2
(-5960 4960);
DISPLAY 0.489362 (-5960 4960);
WIRE 17 -1 (-5725 4850)(-5725 4750);
WIRE 17 -1 (-5725 4750)(-5725 4650);
WIRE 17 -1 (-5725 4650)(-5725 4550);
WIRE 17 -1 (-5725 4450)(-5725 4550);
WIRE 17 -1 (-5725 4350)(-5725 4450);
WIRE 17 -1 (-5725 4250)(-5725 4350);
WIRE 17 -1 (-5725 4250)(-5725 4150);
WIRE 17 -1 (-5725 4150)(-5725 4050);
WIRE 17 -1 (-5925 4900)(-5925 4800);
FORCEPROP 2 LAST SIG_NAME M_I_CPU0_SB_DQS_DN<9:0>
J 2
(-5960 4910);
DISPLAY 0.489362 (-5960 4910);
WIRE 17 -1 (-5925 4800)(-5925 4700);
WIRE 17 -1 (-5925 4700)(-5925 4600);
WIRE 17 -1 (-5925 4600)(-5925 4500);
WIRE 17 -1 (-5925 4400)(-5925 4500);
WIRE 17 -1 (-5925 4300)(-5925 4400);
WIRE 17 -1 (-5925 4200)(-5925 4300);
WIRE 17 -1 (-5925 4200)(-5925 4100);
WIRE 17 -1 (-5925 4100)(-5925 4000);
WIRE 17 -1 (-5925 3800)(-5925 3850);
WIRE 17 -1 (-5925 3750)(-5925 3800);
WIRE 17 -1 (-5925 3850)(-6425 3850);
FORCEPROP 2 LAST SIG_NAME M_I_CPU0_SA_CA<6:0>
J 0
(-6425 3860);
DISPLAY 0.489362 (-6425 3860);
WIRE 17 -1 (-5925 3400)(-5925 3450);
WIRE 17 -1 (-5925 3350)(-5925 3400);
WIRE 17 -1 (-5925 3450)(-6425 3450);
FORCEPROP 2 LAST SIG_NAME M_I_CPU0_SB_CA<6:0>
J 0
(-6425 3460);
DISPLAY 0.489362 (-6425 3460);
WIRE 17 -1 (-5925 3700)(-5925 3750);
WIRE 17 -1 (-5925 3300)(-5925 3350);
WIRE 17 -1 (-5925 3650)(-5925 3700);
WIRE 17 -1 (-5925 3600)(-5925 3650);
WIRE 17 -1 (-5925 3550)(-5925 3600);
WIRE 17 -1 (-5925 3250)(-5925 3300);
WIRE 17 -1 (-5925 3200)(-5925 3250);
WIRE 17 -1 (-5925 3150)(-5925 3200);
WIRE 17 -1 (-5925 5950)(-6525 5950);
WIRE 17 -1 (-5925 4900)(-6525 4900);
WIRE 16 -1 (-7625 2125)(-6900 2125);
FORCEPROP 2 LAST SIG_NAME M_I_CPU0_ALERT_N
J 0
(-7585 2135);
DISPLAY 0.489362 (-7585 2135);
WIRE 16 -1 (-6700 2125)(-5325 2125);
FORCEPROP 2 LAST SIG_NAME M_I_CPU0_ALERT_R_N
J 0
(-6410 2135);
DISPLAY 0.489362 (-6410 2135);
FORCEPROP 2 LASTPROP $XRERR UNIQUE?
J 0
(-6650 2135);
DISPLAY 0.638298 (-6650 2135);
PAINT MONO (-6650 2135);
DISPLAY INVISIBLE (-6650 2135);
WIRE 16 -1 (-6425 1175)(-5325 1175);
FORCEPROP 2 LAST SIG_NAME TP_M_I_CPU0_SA_TEST39I
J 0
(-6410 1185);
DISPLAY 0.489362 (-6410 1185);
FORCEPROP 2 LASTPROP $XRERR UNIQUE?
J 0
(-6665 1175);
DISPLAY 0.638298 (-6665 1175);
PAINT MONO (-6665 1175);
DISPLAY INVISIBLE (-6665 1175);
WIRE 16 -1 (-6425 2975)(-5325 2975);
FORCEPROP 2 LAST SIG_NAME M_I_CPU0_CLK_DP<0>
J 0
(-6425 2985);
DISPLAY 0.489362 (-6425 2985);
WIRE 16 -1 (-6425 2925)(-5325 2925);
FORCEPROP 2 LAST SIG_NAME M_I_CPU0_CLK_DN<0>
J 0
(-6425 2935);
DISPLAY 0.489362 (-6425 2935);
WIRE 16 -1 (-6425 2825)(-5325 2825);
FORCEPROP 2 LAST SIG_NAME M_I_CPU0_SA_CS_N<0>
J 0
(-6425 2835);
DISPLAY 0.489362 (-6425 2835);
WIRE 16 -1 (-6425 2775)(-5325 2775);
FORCEPROP 2 LAST SIG_NAME M_I_CPU0_SA_CS_N<1>
J 0
(-6425 2785);
DISPLAY 0.489362 (-6425 2785);
WIRE 16 -1 (-6425 2675)(-5325 2675);
FORCEPROP 2 LAST SIG_NAME M_I_CPU0_SA_RSP<0>
J 0
(-6425 2685);
DISPLAY 0.489362 (-6425 2685);
WIRE 16 -1 (-6425 2575)(-5325 2575);
FORCEPROP 2 LAST SIG_NAME M_I_CPU0_SA_PAR
J 0
(-6425 2585);
DISPLAY 0.489362 (-6425 2585);
WIRE 16 -1 (-6425 2475)(-5325 2475);
FORCEPROP 2 LAST SIG_NAME M_I_CPU0_SB_CS_N<0>
J 0
(-6425 2485);
DISPLAY 0.489362 (-6425 2485);
WIRE 16 -1 (-6425 2425)(-5325 2425);
FORCEPROP 2 LAST SIG_NAME M_I_CPU0_SB_CS_N<1>
J 0
(-6425 2435);
DISPLAY 0.489362 (-6425 2435);
WIRE 16 -1 (-6425 2325)(-5325 2325);
FORCEPROP 2 LAST SIG_NAME M_I_CPU0_SB_RSP<0>
J 0
(-6425 2335);
DISPLAY 0.489362 (-6425 2335);
WIRE 16 -1 (-6425 2225)(-5325 2225);
FORCEPROP 2 LAST SIG_NAME M_I_CPU0_SB_PAR
J 0
(-6425 2235);
DISPLAY 0.489362 (-6425 2235);
WIRE 16 -1 (-6425 2025)(-5325 2025);
FORCEPROP 2 LAST SIG_NAME M_I_CPU0_RESET_N
J 0
(-6425 2035);
DISPLAY 0.489362 (-6425 2035);
WIRE 16 -1 (-5825 3975)(-5325 3975);
WIRE 16 -1 (-5825 4075)(-5325 4075);
WIRE 16 -1 (-5825 3125)(-5325 3125);
WIRE 16 -1 (-5825 3525)(-5325 3525);
WIRE 16 -1 (-5825 3175)(-5325 3175);
WIRE 16 -1 (-5825 3575)(-5325 3575);
WIRE 16 -1 (-5825 3225)(-5325 3225);
WIRE 16 -1 (-5825 3625)(-5325 3625);
WIRE 16 -1 (-5825 3275)(-5325 3275);
WIRE 16 -1 (-5825 3675)(-5325 3675);
WIRE 16 -1 (-5825 3325)(-5325 3325);
WIRE 16 -1 (-5825 3725)(-5325 3725);
WIRE 16 -1 (-5825 3375)(-5325 3375);
WIRE 16 -1 (-5825 3775)(-5325 3775);
WIRE 16 -1 (-5825 3425)(-5325 3425);
WIRE 16 -1 (-5825 3825)(-5325 3825);
WIRE 16 -1 (-5625 4025)(-5325 4025);
WIRE 16 -1 (-5825 4175)(-5325 4175);
WIRE 16 -1 (-5825 4275)(-5325 4275);
WIRE 16 -1 (-5825 4375)(-5325 4375);
WIRE 16 -1 (-5825 4475)(-5325 4475);
WIRE 16 -1 (-5825 5025)(-5325 5025);
WIRE 16 -1 (-5825 4575)(-5325 4575);
WIRE 16 -1 (-5825 4675)(-5325 4675);
WIRE 16 -1 (-5825 4775)(-5325 4775);
WIRE 16 -1 (-5825 4875)(-5325 4875);
WIRE 16 -1 (-5625 4125)(-5325 4125);
WIRE 16 -1 (-5625 4225)(-5325 4225);
WIRE 16 -1 (-5625 4325)(-5325 4325);
WIRE 16 -1 (-5625 4425)(-5325 4425);
WIRE 16 -1 (-5625 4525)(-5325 4525);
WIRE 16 -1 (-5625 5075)(-5325 5075);
WIRE 16 -1 (-5625 4625)(-5325 4625);
WIRE 16 -1 (-5625 4725)(-5325 4725);
WIRE 16 -1 (-5625 4825)(-5325 4825);
WIRE 16 -1 (-5625 4925)(-5325 4925);
WIRE 16 -1 (-5825 5525)(-5325 5525);
WIRE 16 -1 (-5825 5625)(-5325 5625);
WIRE 16 -1 (-5825 5725)(-5325 5725);
WIRE 16 -1 (-5825 5825)(-5325 5825);
WIRE 16 -1 (-5825 5925)(-5325 5925);
WIRE 16 -1 (-5825 5125)(-5325 5125);
WIRE 16 -1 (-5825 5225)(-5325 5225);
WIRE 16 -1 (-5825 5325)(-5325 5325);
WIRE 16 -1 (-5825 5425)(-5325 5425);
WIRE 16 -1 (-5625 5175)(-5325 5175);
WIRE 16 -1 (-5625 5275)(-5325 5275);
WIRE 16 -1 (-5625 5375)(-5325 5375);
WIRE 16 -1 (-5625 5475)(-5325 5475);
WIRE 16 -1 (-5625 5575)(-5325 5575);
WIRE 16 -1 (-5625 5975)(-5325 5975);
WIRE 16 -1 (-5625 5675)(-5325 5675);
WIRE 16 -1 (-5625 5775)(-5325 5775);
WIRE 16 -1 (-5625 5875)(-5325 5875);
WIRE 16 -1 (-3725 1825)(-3300 1825);
WIRE 16 -1 (-3725 2025)(-3300 2025);
WIRE 16 -1 (-3725 1875)(-3300 1875);
WIRE 16 -1 (-3725 1925)(-3300 1925);
WIRE 16 -1 (-3725 1575)(-3300 1575);
WIRE 16 -1 (-3725 1625)(-3300 1625);
WIRE 16 -1 (-3725 1675)(-3300 1675);
WIRE 16 -1 (-3725 1725)(-3300 1725);
WIRE 16 -1 (-3725 1775)(-3300 1775);
WIRE 16 -1 (-3725 2975)(-3300 2975);
WIRE 16 -1 (-3725 3025)(-3300 3025);
WIRE 16 -1 (-3725 2075)(-3300 2075);
WIRE 16 -1 (-3725 2475)(-3300 2475);
WIRE 16 -1 (-3725 2125)(-3300 2125);
WIRE 16 -1 (-3725 2525)(-3300 2525);
WIRE 16 -1 (-3725 2175)(-3300 2175);
WIRE 16 -1 (-3725 2225)(-3300 2225);
WIRE 16 -1 (-3725 2275)(-3300 2275);
WIRE 16 -1 (-3725 2325)(-3300 2325);
WIRE 16 -1 (-3725 2375)(-3300 2375);
WIRE 16 -1 (-3725 2575)(-3300 2575);
WIRE 16 -1 (-3725 2625)(-3300 2625);
WIRE 16 -1 (-3725 2675)(-3300 2675);
WIRE 16 -1 (-3725 2725)(-3300 2725);
WIRE 16 -1 (-3725 2775)(-3300 2775);
WIRE 16 -1 (-3725 2825)(-3300 2825);
WIRE 16 -1 (-3725 2925)(-3300 2925);
WIRE 16 -1 (-3725 3925)(-3300 3925);
WIRE 16 -1 (-3725 3575)(-3300 3575);
WIRE 16 -1 (-3725 3975)(-3300 3975);
WIRE 16 -1 (-3725 3625)(-3300 3625);
WIRE 16 -1 (-3725 4025)(-3300 4025);
WIRE 16 -1 (-3725 3075)(-3300 3075);
WIRE 16 -1 (-3725 4075)(-3300 4075);
WIRE 16 -1 (-3725 3125)(-3300 3125);
WIRE 16 -1 (-3725 3175)(-3300 3175);
WIRE 16 -1 (-3725 3225)(-3300 3225);
WIRE 16 -1 (-3725 3275)(-3300 3275);
WIRE 16 -1 (-3725 3675)(-3300 3675);
WIRE 16 -1 (-3725 3375)(-3300 3375);
WIRE 16 -1 (-3725 3725)(-3300 3725);
WIRE 16 -1 (-3725 3425)(-3300 3425);
WIRE 16 -1 (-3725 3825)(-3300 3825);
WIRE 16 -1 (-3725 3475)(-3300 3475);
WIRE 16 -1 (-3725 3875)(-3300 3875);
WIRE 16 -1 (-3725 3525)(-3300 3525);
WIRE 16 -1 (-3725 5025)(-3300 5025);
WIRE 16 -1 (-3725 4425)(-3300 4425);
WIRE 16 -1 (-3725 5075)(-3300 5075);
WIRE 16 -1 (-3725 4475)(-3300 4475);
WIRE 16 -1 (-3725 4525)(-3300 4525);
WIRE 16 -1 (-3725 4575)(-3300 4575);
WIRE 16 -1 (-3725 4625)(-3300 4625);
WIRE 16 -1 (-3725 4125)(-3300 4125);
WIRE 16 -1 (-3725 4725)(-3300 4725);
WIRE 16 -1 (-3725 4175)(-3300 4175);
WIRE 16 -1 (-3725 4775)(-3300 4775);
WIRE 16 -1 (-3725 4825)(-3300 4825);
WIRE 16 -1 (-3725 4875)(-3300 4875);
WIRE 16 -1 (-3725 4275)(-3300 4275);
WIRE 16 -1 (-3725 4325)(-3300 4325);
WIRE 16 -1 (-3725 4925)(-3300 4925);
WIRE 16 -1 (-3725 4975)(-3300 4975);
WIRE 16 -1 (-3725 4375)(-3300 4375);
WIRE 16 -1 (-3725 5725)(-3300 5725);
WIRE 16 -1 (-3725 5775)(-3300 5775);
WIRE 16 -1 (-3725 5825)(-3300 5825);
WIRE 16 -1 (-3725 5175)(-3300 5175);
WIRE 16 -1 (-3725 5875)(-3300 5875);
WIRE 16 -1 (-3725 5225)(-3300 5225);
WIRE 16 -1 (-3725 5925)(-3300 5925);
WIRE 16 -1 (-3725 5275)(-3300 5275);
WIRE 16 -1 (-3725 5975)(-3300 5975);
WIRE 16 -1 (-3725 5325)(-3300 5325);
WIRE 16 -1 (-3725 5375)(-3300 5375);
WIRE 16 -1 (-3725 5425)(-3300 5425);
WIRE 16 -1 (-3725 5475)(-3300 5475);
WIRE 16 -1 (-3725 5525)(-3300 5525);
WIRE 16 -1 (-3725 5625)(-3300 5625);
WIRE 16 -1 (-3725 5675)(-3300 5675);
QUIT
